FILE_TYPE = MACRO_DRAWING;
SET COLOR_WIRE YELLOW;
SET COLOR_PROP ORANGE;
SET COLOR_DOT WHITE;
SET COLOR_ARC YELLOW;
SET COLOR_BODY GREEN;
SET COLOR_NOTE PURPLE;
SET PROP_DISPLAY VALUE;
SET PAGE_NUMBER P14;
FORCEADD GENOA_SP5..5
(-4675 3675);
FORCEPROP 1 LAST LOCATION U25
J 0
(-5320 6506);
DISPLAY 0.489362 (-5320 6506);
PAINT SKYBLUE (-5320 6506);
FORCEPROP 0 LAST $SEC 5
J 0
(-5300 6550);
DISPLAY 0.680851 (-5300 6550);
PAINT MONO (-5300 6550);
DISPLAY INVISIBLE (-5300 6550);
FORCEPROP 0 LAST CDS_SEC 5
J 0
(-5325 6500);
DISPLAY 1.021277 (-5325 6500);
DISPLAY INVISIBLE (-5325 6500);
FORCEPROP 0 LASTPIN (-5475 3050) $PN BC71
J 2
(-5485 3060);
DISPLAY 0.489362 (-5485 3060);
PAINT MONO (-5485 3060);
FORCEPROP 0 LASTPIN (-5475 3000) $PN BD70
J 2
(-5485 3010);
DISPLAY 0.489362 (-5485 3010);
PAINT MONO (-5485 3010);
FORCEPROP 0 LASTPIN (-5475 1900) $PN BF70
J 2
(-5485 1910);
DISPLAY 0.489362 (-5485 1910);
PAINT MONO (-5485 1910);
FORCEPROP 0 LASTPIN (-5475 1850) $PN BG71
J 2
(-5485 1860);
DISPLAY 0.489362 (-5485 1860);
PAINT MONO (-5485 1860);
FORCEPROP 0 LASTPIN (-5475 2200) $PN AT69
J 2
(-5485 2210);
DISPLAY 0.489362 (-5485 2210);
PAINT MONO (-5485 2210);
FORCEPROP 0 LASTPIN (-5475 2100) $PN AU69
J 2
(-5485 2110);
DISPLAY 0.489362 (-5485 2110);
PAINT MONO (-5485 2110);
FORCEPROP 0 LASTPIN (-5475 2900) $PN AV70
J 2
(-5485 2910);
DISPLAY 0.489362 (-5485 2910);
PAINT MONO (-5485 2910);
FORCEPROP 0 LASTPIN (-5475 2850) $PN AW69
J 2
(-5485 2860);
DISPLAY 0.489362 (-5485 2860);
PAINT MONO (-5485 2860);
FORCEPROP 0 LASTPIN (-5475 2750) $PN BN69
J 2
(-5485 2760);
DISPLAY 0.489362 (-5485 2760);
PAINT MONO (-5485 2760);
FORCEPROP 0 LASTPIN (-5475 1750) $PN AU71
J 2
(-5485 1760);
DISPLAY 0.489362 (-5485 1760);
PAINT MONO (-5485 1760);
FORCEPROP 0 LASTPIN (-5475 1700) $PN AV69
J 2
(-5485 1710);
DISPLAY 0.489362 (-5485 1710);
PAINT MONO (-5485 1710);
FORCEPROP 0 LASTPIN (-5475 1600) $PN BP69
J 2
(-5485 1610);
DISPLAY 0.489362 (-5485 1610);
PAINT MONO (-5485 1610);
FORCEPROP 0 LASTPIN (-5475 3900) $PN AW71
J 2
(-5485 3910);
DISPLAY 0.489362 (-5485 3910);
PAINT MONO (-5485 3910);
FORCEPROP 0 LASTPIN (-5475 3850) $PN AY70
J 2
(-5485 3860);
DISPLAY 0.489362 (-5485 3860);
PAINT MONO (-5485 3860);
FORCEPROP 0 LASTPIN (-5475 3800) $PN AY69
J 2
(-5485 3810);
DISPLAY 0.489362 (-5485 3810);
PAINT MONO (-5485 3810);
FORCEPROP 0 LASTPIN (-5475 3750) $PN BA69
J 2
(-5485 3760);
DISPLAY 0.489362 (-5485 3760);
PAINT MONO (-5485 3760);
FORCEPROP 0 LASTPIN (-5475 3700) $PN BA71
J 2
(-5485 3710);
DISPLAY 0.489362 (-5485 3710);
PAINT MONO (-5485 3710);
FORCEPROP 0 LASTPIN (-5475 3650) $PN BB70
J 2
(-5485 3660);
DISPLAY 0.489362 (-5485 3660);
PAINT MONO (-5485 3660);
FORCEPROP 0 LASTPIN (-5475 3600) $PN BB69
J 2
(-5485 3610);
DISPLAY 0.489362 (-5485 3610);
PAINT MONO (-5485 3610);
FORCEPROP 0 LASTPIN (-3875 2450) $PN AJ71
J 0
(-3865 2460);
DISPLAY 0.489362 (-3865 2460);
PAINT MONO (-3865 2460);
FORCEPROP 0 LASTPIN (-3875 2400) $PN AK69
J 0
(-3865 2410);
DISPLAY 0.489362 (-3865 2410);
PAINT MONO (-3865 2410);
FORCEPROP 0 LASTPIN (-3875 2350) $PN AK70
J 0
(-3865 2360);
DISPLAY 0.489362 (-3865 2360);
PAINT MONO (-3865 2360);
FORCEPROP 0 LASTPIN (-3875 2300) $PN AL69
J 0
(-3865 2310);
DISPLAY 0.489362 (-3865 2310);
PAINT MONO (-3865 2310);
FORCEPROP 0 LASTPIN (-3875 2250) $PN AN71
J 0
(-3865 2260);
DISPLAY 0.489362 (-3865 2260);
PAINT MONO (-3865 2260);
FORCEPROP 0 LASTPIN (-3875 2200) $PN AP69
J 0
(-3865 2210);
DISPLAY 0.489362 (-3865 2210);
PAINT MONO (-3865 2210);
FORCEPROP 0 LASTPIN (-3875 2150) $PN AP70
J 0
(-3865 2160);
DISPLAY 0.489362 (-3865 2160);
PAINT MONO (-3865 2160);
FORCEPROP 0 LASTPIN (-3875 2100) $PN AR69
J 0
(-3865 2110);
DISPLAY 0.489362 (-3865 2110);
PAINT MONO (-3865 2110);
FORCEPROP 0 LASTPIN (-3875 6050) $PN E71
J 0
(-3865 6060);
DISPLAY 0.489362 (-3865 6060);
PAINT MONO (-3865 6060);
FORCEPROP 0 LASTPIN (-3875 6000) $PN F69
J 0
(-3865 6010);
DISPLAY 0.489362 (-3865 6010);
PAINT MONO (-3865 6010);
FORCEPROP 0 LASTPIN (-3875 5950) $PN F70
J 0
(-3865 5960);
DISPLAY 0.489362 (-3865 5960);
PAINT MONO (-3865 5960);
FORCEPROP 0 LASTPIN (-3875 5900) $PN G69
J 0
(-3865 5910);
DISPLAY 0.489362 (-3865 5910);
PAINT MONO (-3865 5910);
FORCEPROP 0 LASTPIN (-3875 5850) $PN J71
J 0
(-3865 5860);
DISPLAY 0.489362 (-3865 5860);
PAINT MONO (-3865 5860);
FORCEPROP 0 LASTPIN (-3875 5800) $PN K69
J 0
(-3865 5810);
DISPLAY 0.489362 (-3865 5810);
PAINT MONO (-3865 5810);
FORCEPROP 0 LASTPIN (-3875 5750) $PN K70
J 0
(-3865 5760);
DISPLAY 0.489362 (-3865 5760);
PAINT MONO (-3865 5760);
FORCEPROP 0 LASTPIN (-3875 5700) $PN L69
J 0
(-3865 5710);
DISPLAY 0.489362 (-3865 5710);
PAINT MONO (-3865 5710);
FORCEPROP 0 LASTPIN (-3875 5600) $PN L71
J 0
(-3865 5610);
DISPLAY 0.489362 (-3865 5610);
PAINT MONO (-3865 5610);
FORCEPROP 0 LASTPIN (-3875 5550) $PN M69
J 0
(-3865 5560);
DISPLAY 0.489362 (-3865 5560);
PAINT MONO (-3865 5560);
FORCEPROP 0 LASTPIN (-3875 5500) $PN M70
J 0
(-3865 5510);
DISPLAY 0.489362 (-3865 5510);
PAINT MONO (-3865 5510);
FORCEPROP 0 LASTPIN (-3875 5450) $PN N69
J 0
(-3865 5460);
DISPLAY 0.489362 (-3865 5460);
PAINT MONO (-3865 5460);
FORCEPROP 0 LASTPIN (-3875 5400) $PN R71
J 0
(-3865 5410);
DISPLAY 0.489362 (-3865 5410);
PAINT MONO (-3865 5410);
FORCEPROP 0 LASTPIN (-3875 5350) $PN T69
J 0
(-3865 5360);
DISPLAY 0.489362 (-3865 5360);
PAINT MONO (-3865 5360);
FORCEPROP 0 LASTPIN (-3875 5300) $PN T70
J 0
(-3865 5310);
DISPLAY 0.489362 (-3865 5310);
PAINT MONO (-3865 5310);
FORCEPROP 0 LASTPIN (-3875 5250) $PN U69
J 0
(-3865 5260);
DISPLAY 0.489362 (-3865 5260);
PAINT MONO (-3865 5260);
FORCEPROP 0 LASTPIN (-3875 5150) $PN U71
J 0
(-3865 5160);
DISPLAY 0.489362 (-3865 5160);
PAINT MONO (-3865 5160);
FORCEPROP 0 LASTPIN (-3875 5100) $PN V69
J 0
(-3865 5110);
DISPLAY 0.489362 (-3865 5110);
PAINT MONO (-3865 5110);
FORCEPROP 0 LASTPIN (-3875 5050) $PN V70
J 0
(-3865 5060);
DISPLAY 0.489362 (-3865 5060);
PAINT MONO (-3865 5060);
FORCEPROP 0 LASTPIN (-3875 5000) $PN W69
J 0
(-3865 5010);
DISPLAY 0.489362 (-3865 5010);
PAINT MONO (-3865 5010);
FORCEPROP 0 LASTPIN (-3875 4950) $PN AA71
J 0
(-3865 4960);
DISPLAY 0.489362 (-3865 4960);
PAINT MONO (-3865 4960);
FORCEPROP 0 LASTPIN (-3875 4900) $PN AB69
J 0
(-3865 4910);
DISPLAY 0.489362 (-3865 4910);
PAINT MONO (-3865 4910);
FORCEPROP 0 LASTPIN (-3875 4850) $PN AB70
J 0
(-3865 4860);
DISPLAY 0.489362 (-3865 4860);
PAINT MONO (-3865 4860);
FORCEPROP 0 LASTPIN (-3875 4800) $PN AC69
J 0
(-3865 4810);
DISPLAY 0.489362 (-3865 4810);
PAINT MONO (-3865 4810);
FORCEPROP 0 LASTPIN (-3875 4700) $PN AC71
J 0
(-3865 4710);
DISPLAY 0.489362 (-3865 4710);
PAINT MONO (-3865 4710);
FORCEPROP 0 LASTPIN (-3875 4650) $PN AD69
J 0
(-3865 4660);
DISPLAY 0.489362 (-3865 4660);
PAINT MONO (-3865 4660);
FORCEPROP 0 LASTPIN (-3875 4600) $PN AD70
J 0
(-3865 4610);
DISPLAY 0.489362 (-3865 4610);
PAINT MONO (-3865 4610);
FORCEPROP 0 LASTPIN (-3875 4550) $PN AE69
J 0
(-3865 4560);
DISPLAY 0.489362 (-3865 4560);
PAINT MONO (-3865 4560);
FORCEPROP 0 LASTPIN (-3875 4500) $PN AG71
J 0
(-3865 4510);
DISPLAY 0.489362 (-3865 4510);
PAINT MONO (-3865 4510);
FORCEPROP 0 LASTPIN (-3875 4450) $PN AH69
J 0
(-3865 4460);
DISPLAY 0.489362 (-3865 4460);
PAINT MONO (-3865 4460);
FORCEPROP 0 LASTPIN (-3875 4400) $PN AH70
J 0
(-3865 4410);
DISPLAY 0.489362 (-3865 4410);
PAINT MONO (-3865 4410);
FORCEPROP 0 LASTPIN (-3875 4350) $PN AJ69
J 0
(-3865 4360);
DISPLAY 0.489362 (-3865 4360);
PAINT MONO (-3865 4360);
FORCEPROP 0 LASTPIN (-5475 6050) $PN G71
J 2
(-5485 6060);
DISPLAY 0.489362 (-5485 6060);
PAINT MONO (-5485 6060);
FORCEPROP 0 LASTPIN (-5475 5950) $PN N71
J 2
(-5485 5960);
DISPLAY 0.489362 (-5485 5960);
PAINT MONO (-5485 5960);
FORCEPROP 0 LASTPIN (-5475 5850) $PN W71
J 2
(-5485 5860);
DISPLAY 0.489362 (-5485 5860);
PAINT MONO (-5485 5860);
FORCEPROP 0 LASTPIN (-5475 5750) $PN AE71
J 2
(-5485 5760);
DISPLAY 0.489362 (-5485 5760);
PAINT MONO (-5485 5760);
FORCEPROP 0 LASTPIN (-5475 5650) $PN AL71
J 2
(-5485 5660);
DISPLAY 0.489362 (-5485 5660);
PAINT MONO (-5485 5660);
FORCEPROP 0 LASTPIN (-5475 5550) $PN J69
J 2
(-5485 5560);
DISPLAY 0.489362 (-5485 5560);
PAINT MONO (-5485 5560);
FORCEPROP 0 LASTPIN (-5475 5450) $PN R69
J 2
(-5485 5460);
DISPLAY 0.489362 (-5485 5460);
PAINT MONO (-5485 5460);
FORCEPROP 0 LASTPIN (-5475 5350) $PN AA69
J 2
(-5485 5360);
DISPLAY 0.489362 (-5485 5360);
PAINT MONO (-5485 5360);
FORCEPROP 0 LASTPIN (-5475 5250) $PN AG69
J 2
(-5485 5260);
DISPLAY 0.489362 (-5485 5260);
PAINT MONO (-5485 5260);
FORCEPROP 0 LASTPIN (-5475 5150) $PN AN69
J 2
(-5485 5160);
DISPLAY 0.489362 (-5485 5160);
PAINT MONO (-5485 5160);
FORCEPROP 0 LASTPIN (-5475 6000) $PN H70
J 2
(-5485 6010);
DISPLAY 0.489362 (-5485 6010);
PAINT MONO (-5485 6010);
FORCEPROP 0 LASTPIN (-5475 5900) $PN P70
J 2
(-5485 5910);
DISPLAY 0.489362 (-5485 5910);
PAINT MONO (-5485 5910);
FORCEPROP 0 LASTPIN (-5475 5800) $PN Y70
J 2
(-5485 5810);
DISPLAY 0.489362 (-5485 5810);
PAINT MONO (-5485 5810);
FORCEPROP 0 LASTPIN (-5475 5700) $PN AF70
J 2
(-5485 5710);
DISPLAY 0.489362 (-5485 5710);
PAINT MONO (-5485 5710);
FORCEPROP 0 LASTPIN (-5475 5600) $PN AM70
J 2
(-5485 5610);
DISPLAY 0.489362 (-5485 5610);
PAINT MONO (-5485 5610);
FORCEPROP 0 LASTPIN (-5475 5500) $PN H69
J 2
(-5485 5510);
DISPLAY 0.489362 (-5485 5510);
PAINT MONO (-5485 5510);
FORCEPROP 0 LASTPIN (-5475 5400) $PN P69
J 2
(-5485 5410);
DISPLAY 0.489362 (-5485 5410);
PAINT MONO (-5485 5410);
FORCEPROP 0 LASTPIN (-5475 5300) $PN Y69
J 2
(-5485 5310);
DISPLAY 0.489362 (-5485 5310);
PAINT MONO (-5485 5310);
FORCEPROP 0 LASTPIN (-5475 5200) $PN AF69
J 2
(-5485 5210);
DISPLAY 0.489362 (-5485 5210);
PAINT MONO (-5485 5210);
FORCEPROP 0 LASTPIN (-5475 5100) $PN AM69
J 2
(-5485 5110);
DISPLAY 0.489362 (-5485 5110);
PAINT MONO (-5485 5110);
FORCEPROP 0 LASTPIN (-5475 2650) $PN BC69
J 2
(-5485 2660);
DISPLAY 0.489362 (-5485 2660);
PAINT MONO (-5485 2660);
FORCEPROP 0 LASTPIN (-5475 2550) $PN BM69
J 2
(-5485 2560);
DISPLAY 0.489362 (-5485 2560);
PAINT MONO (-5485 2560);
FORCEPROP 0 LASTPIN (-5475 2500) $PN BN71
J 2
(-5485 2510);
DISPLAY 0.489362 (-5485 2510);
PAINT MONO (-5485 2510);
FORCEPROP 0 LASTPIN (-5475 2400) $PN BP70
J 2
(-5485 2410);
DISPLAY 0.489362 (-5485 2410);
PAINT MONO (-5485 2410);
FORCEPROP 0 LASTPIN (-5475 1500) $PN BL69
J 2
(-5485 1510);
DISPLAY 0.489362 (-5485 1510);
PAINT MONO (-5485 1510);
FORCEPROP 0 LASTPIN (-5475 1450) $PN BM70
J 2
(-5485 1460);
DISPLAY 0.489362 (-5485 1460);
PAINT MONO (-5485 1460);
FORCEPROP 0 LASTPIN (-5475 1350) $PN BR71
J 2
(-5485 1360);
DISPLAY 0.489362 (-5485 1360);
PAINT MONO (-5485 1360);
FORCEPROP 0 LASTPIN (-5475 3500) $PN BG69
J 2
(-5485 3510);
DISPLAY 0.489362 (-5485 3510);
PAINT MONO (-5485 3510);
FORCEPROP 0 LASTPIN (-5475 3450) $PN BH69
J 2
(-5485 3460);
DISPLAY 0.489362 (-5485 3460);
PAINT MONO (-5485 3460);
FORCEPROP 0 LASTPIN (-5475 3400) $PN BH70
J 2
(-5485 3410);
DISPLAY 0.489362 (-5485 3410);
PAINT MONO (-5485 3410);
FORCEPROP 0 LASTPIN (-5475 3350) $PN BJ71
J 2
(-5485 3360);
DISPLAY 0.489362 (-5485 3360);
PAINT MONO (-5485 3360);
FORCEPROP 0 LASTPIN (-5475 3300) $PN BJ69
J 2
(-5485 3310);
DISPLAY 0.489362 (-5485 3310);
PAINT MONO (-5485 3310);
FORCEPROP 0 LASTPIN (-5475 3250) $PN BK69
J 2
(-5485 3260);
DISPLAY 0.489362 (-5485 3260);
PAINT MONO (-5485 3260);
FORCEPROP 0 LASTPIN (-5475 3200) $PN BK70
J 2
(-5485 3210);
DISPLAY 0.489362 (-5485 3210);
PAINT MONO (-5485 3210);
FORCEPROP 0 LASTPIN (-3875 2000) $PN BY70
J 0
(-3865 2010);
DISPLAY 0.489362 (-3865 2010);
PAINT MONO (-3865 2010);
FORCEPROP 0 LASTPIN (-3875 1950) $PN CA69
J 0
(-3865 1960);
DISPLAY 0.489362 (-3865 1960);
PAINT MONO (-3865 1960);
FORCEPROP 0 LASTPIN (-3875 1900) $PN CA71
J 0
(-3865 1910);
DISPLAY 0.489362 (-3865 1910);
PAINT MONO (-3865 1910);
FORCEPROP 0 LASTPIN (-3875 1850) $PN CB69
J 0
(-3865 1860);
DISPLAY 0.489362 (-3865 1860);
PAINT MONO (-3865 1860);
FORCEPROP 0 LASTPIN (-3875 1800) $PN BT70
J 0
(-3865 1810);
DISPLAY 0.489362 (-3865 1810);
PAINT MONO (-3865 1810);
FORCEPROP 0 LASTPIN (-3875 1750) $PN BU69
J 0
(-3865 1760);
DISPLAY 0.489362 (-3865 1760);
PAINT MONO (-3865 1760);
FORCEPROP 0 LASTPIN (-3875 1700) $PN BU71
J 0
(-3865 1710);
DISPLAY 0.489362 (-3865 1710);
PAINT MONO (-3865 1710);
FORCEPROP 0 LASTPIN (-3875 1650) $PN BV69
J 0
(-3865 1660);
DISPLAY 0.489362 (-3865 1660);
PAINT MONO (-3865 1660);
FORCEPROP 0 LASTPIN (-3875 4250) $PN CB70
J 0
(-3865 4260);
DISPLAY 0.489362 (-3865 4260);
PAINT MONO (-3865 4260);
FORCEPROP 0 LASTPIN (-3875 4200) $PN CC69
J 0
(-3865 4210);
DISPLAY 0.489362 (-3865 4210);
PAINT MONO (-3865 4210);
FORCEPROP 0 LASTPIN (-3875 4150) $PN CC71
J 0
(-3865 4160);
DISPLAY 0.489362 (-3865 4160);
PAINT MONO (-3865 4160);
FORCEPROP 0 LASTPIN (-3875 4100) $PN CD69
J 0
(-3865 4110);
DISPLAY 0.489362 (-3865 4110);
PAINT MONO (-3865 4110);
FORCEPROP 0 LASTPIN (-3875 4050) $PN CF70
J 0
(-3865 4060);
DISPLAY 0.489362 (-3865 4060);
PAINT MONO (-3865 4060);
FORCEPROP 0 LASTPIN (-3875 4000) $PN CG69
J 0
(-3865 4010);
DISPLAY 0.489362 (-3865 4010);
PAINT MONO (-3865 4010);
FORCEPROP 0 LASTPIN (-3875 3950) $PN CG71
J 0
(-3865 3960);
DISPLAY 0.489362 (-3865 3960);
PAINT MONO (-3865 3960);
FORCEPROP 0 LASTPIN (-3875 3900) $PN CH69
J 0
(-3865 3910);
DISPLAY 0.489362 (-3865 3910);
PAINT MONO (-3865 3910);
FORCEPROP 0 LASTPIN (-3875 3800) $PN CH70
J 0
(-3865 3810);
DISPLAY 0.489362 (-3865 3810);
PAINT MONO (-3865 3810);
FORCEPROP 0 LASTPIN (-3875 3750) $PN CJ69
J 0
(-3865 3760);
DISPLAY 0.489362 (-3865 3760);
PAINT MONO (-3865 3760);
FORCEPROP 0 LASTPIN (-3875 3700) $PN CJ71
J 0
(-3865 3710);
DISPLAY 0.489362 (-3865 3710);
PAINT MONO (-3865 3710);
FORCEPROP 0 LASTPIN (-3875 3650) $PN CK69
J 0
(-3865 3660);
DISPLAY 0.489362 (-3865 3660);
PAINT MONO (-3865 3660);
FORCEPROP 0 LASTPIN (-3875 3600) $PN CM70
J 0
(-3865 3610);
DISPLAY 0.489362 (-3865 3610);
PAINT MONO (-3865 3610);
FORCEPROP 0 LASTPIN (-3875 3550) $PN CN69
J 0
(-3865 3560);
DISPLAY 0.489362 (-3865 3560);
PAINT MONO (-3865 3560);
FORCEPROP 0 LASTPIN (-3875 3500) $PN CN71
J 0
(-3865 3510);
DISPLAY 0.489362 (-3865 3510);
PAINT MONO (-3865 3510);
FORCEPROP 0 LASTPIN (-3875 3450) $PN CP69
J 0
(-3865 3460);
DISPLAY 0.489362 (-3865 3460);
PAINT MONO (-3865 3460);
FORCEPROP 0 LASTPIN (-3875 3350) $PN CP70
J 0
(-3865 3360);
DISPLAY 0.489362 (-3865 3360);
PAINT MONO (-3865 3360);
FORCEPROP 0 LASTPIN (-3875 3300) $PN CR69
J 0
(-3865 3310);
DISPLAY 0.489362 (-3865 3310);
PAINT MONO (-3865 3310);
FORCEPROP 0 LASTPIN (-3875 3250) $PN CR71
J 0
(-3865 3260);
DISPLAY 0.489362 (-3865 3260);
PAINT MONO (-3865 3260);
FORCEPROP 0 LASTPIN (-3875 3200) $PN CT69
J 0
(-3865 3210);
DISPLAY 0.489362 (-3865 3210);
PAINT MONO (-3865 3210);
FORCEPROP 0 LASTPIN (-3875 3150) $PN CV70
J 0
(-3865 3160);
DISPLAY 0.489362 (-3865 3160);
PAINT MONO (-3865 3160);
FORCEPROP 0 LASTPIN (-3875 3100) $PN CW69
J 0
(-3865 3110);
DISPLAY 0.489362 (-3865 3110);
PAINT MONO (-3865 3110);
FORCEPROP 0 LASTPIN (-3875 3050) $PN CW71
J 0
(-3865 3060);
DISPLAY 0.489362 (-3865 3060);
PAINT MONO (-3865 3060);
FORCEPROP 0 LASTPIN (-3875 3000) $PN CY69
J 0
(-3865 3010);
DISPLAY 0.489362 (-3865 3010);
PAINT MONO (-3865 3010);
FORCEPROP 0 LASTPIN (-3875 2900) $PN CY70
J 0
(-3865 2910);
DISPLAY 0.489362 (-3865 2910);
PAINT MONO (-3865 2910);
FORCEPROP 0 LASTPIN (-3875 2850) $PN DA69
J 0
(-3865 2860);
DISPLAY 0.489362 (-3865 2860);
PAINT MONO (-3865 2860);
FORCEPROP 0 LASTPIN (-3875 2800) $PN DA71
J 0
(-3865 2810);
DISPLAY 0.489362 (-3865 2810);
PAINT MONO (-3865 2810);
FORCEPROP 0 LASTPIN (-3875 2750) $PN DB69
J 0
(-3865 2760);
DISPLAY 0.489362 (-3865 2760);
PAINT MONO (-3865 2760);
FORCEPROP 0 LASTPIN (-3875 2700) $PN DD70
J 0
(-3865 2710);
DISPLAY 0.489362 (-3865 2710);
PAINT MONO (-3865 2710);
FORCEPROP 0 LASTPIN (-3875 2650) $PN DE69
J 0
(-3865 2660);
DISPLAY 0.489362 (-3865 2660);
PAINT MONO (-3865 2660);
FORCEPROP 0 LASTPIN (-3875 2600) $PN DE71
J 0
(-3865 2610);
DISPLAY 0.489362 (-3865 2610);
PAINT MONO (-3865 2610);
FORCEPROP 0 LASTPIN (-3875 2550) $PN DF69
J 0
(-3865 2560);
DISPLAY 0.489362 (-3865 2560);
PAINT MONO (-3865 2560);
FORCEPROP 0 LASTPIN (-5475 5000) $PN CD70
J 2
(-5485 5010);
DISPLAY 0.489362 (-5485 5010);
PAINT MONO (-5485 5010);
FORCEPROP 0 LASTPIN (-5475 4900) $PN CK70
J 2
(-5485 4910);
DISPLAY 0.489362 (-5485 4910);
PAINT MONO (-5485 4910);
FORCEPROP 0 LASTPIN (-5475 4800) $PN CT70
J 2
(-5485 4810);
DISPLAY 0.489362 (-5485 4810);
PAINT MONO (-5485 4810);
FORCEPROP 0 LASTPIN (-5475 4700) $PN DB70
J 2
(-5485 4710);
DISPLAY 0.489362 (-5485 4710);
PAINT MONO (-5485 4710);
FORCEPROP 0 LASTPIN (-5475 4600) $PN BY69
J 2
(-5485 4610);
DISPLAY 0.489362 (-5485 4610);
PAINT MONO (-5485 4610);
FORCEPROP 0 LASTPIN (-5475 4500) $PN CF69
J 2
(-5485 4510);
DISPLAY 0.489362 (-5485 4510);
PAINT MONO (-5485 4510);
FORCEPROP 0 LASTPIN (-5475 4400) $PN CM69
J 2
(-5485 4410);
DISPLAY 0.489362 (-5485 4410);
PAINT MONO (-5485 4410);
FORCEPROP 0 LASTPIN (-5475 4300) $PN CV69
J 2
(-5485 4310);
DISPLAY 0.489362 (-5485 4310);
PAINT MONO (-5485 4310);
FORCEPROP 0 LASTPIN (-5475 4200) $PN DD69
J 2
(-5485 4210);
DISPLAY 0.489362 (-5485 4210);
PAINT MONO (-5485 4210);
FORCEPROP 0 LASTPIN (-5475 4100) $PN BV70
J 2
(-5485 4110);
DISPLAY 0.489362 (-5485 4110);
PAINT MONO (-5485 4110);
FORCEPROP 0 LASTPIN (-5475 4950) $PN CE71
J 2
(-5485 4960);
DISPLAY 0.489362 (-5485 4960);
PAINT MONO (-5485 4960);
FORCEPROP 0 LASTPIN (-5475 4850) $PN CL71
J 2
(-5485 4860);
DISPLAY 0.489362 (-5485 4860);
PAINT MONO (-5485 4860);
FORCEPROP 0 LASTPIN (-5475 4750) $PN CU71
J 2
(-5485 4760);
DISPLAY 0.489362 (-5485 4760);
PAINT MONO (-5485 4760);
FORCEPROP 0 LASTPIN (-5475 4650) $PN DC71
J 2
(-5485 4660);
DISPLAY 0.489362 (-5485 4660);
PAINT MONO (-5485 4660);
FORCEPROP 0 LASTPIN (-5475 4550) $PN BW69
J 2
(-5485 4560);
DISPLAY 0.489362 (-5485 4560);
PAINT MONO (-5485 4560);
FORCEPROP 0 LASTPIN (-5475 4450) $PN CE69
J 2
(-5485 4460);
DISPLAY 0.489362 (-5485 4460);
PAINT MONO (-5485 4460);
FORCEPROP 0 LASTPIN (-5475 4350) $PN CL69
J 2
(-5485 4360);
DISPLAY 0.489362 (-5485 4360);
PAINT MONO (-5485 4360);
FORCEPROP 0 LASTPIN (-5475 4250) $PN CU69
J 2
(-5485 4260);
DISPLAY 0.489362 (-5485 4260);
PAINT MONO (-5485 4260);
FORCEPROP 0 LASTPIN (-5475 4150) $PN DC69
J 2
(-5485 4160);
DISPLAY 0.489362 (-5485 4160);
PAINT MONO (-5485 4160);
FORCEPROP 0 LASTPIN (-5475 4050) $PN BW71
J 2
(-5485 4060);
DISPLAY 0.489362 (-5485 4060);
PAINT MONO (-5485 4060);
FORCEPROP 0 LASTPIN (-5475 2300) $PN BL71
J 2
(-5485 2310);
DISPLAY 0.489362 (-5485 2310);
PAINT MONO (-5485 2310);
FORCEPROP 0 LASTPIN (-5475 1250) $PN BF69
J 2
(-5485 1260);
DISPLAY 0.489362 (-5485 1260);
PAINT MONO (-5485 1260);
FORCEPROP 2 LAST PART_TYPE SMLF
J 0
(-5325 6430);
DISPLAY 1.021277 (-5325 6430);
FORCEPROP 1 LAST MATERIAL IO
J 0
(-5320 6232);
DISPLAY 0.489362 (-5320 6232);
PAINT SKYBLUE (-5320 6232);
FORCEPROP 2 LAST VALUE SOCKET6096_13568-001
J 0
(-5325 6330);
DISPLAY 0.489362 (-5325 6330);
PAINT SKYBLUE (-5325 6330);
FORCEPROP 1 LAST PART_NUMBER DGA^6000030
J 0
(-5320 6359);
DISPLAY 0.489362 (-5320 6359);
PAINT SKYBLUE (-5320 6359);
FORCEPROP 2 LAST CDS_LIB pure_quanta
J 0
(-4675 3675);
DISPLAY INVISIBLE (-4675 3675);
FORCEPROP 1 LAST CDS_LMAN_SYM_OUTLINE -650,2525,650,-2525
J 0
(-4675 3675);
DISPLAY 0.468085 (-4675 3675);
PAINT GREEN (-4675 3675);
DISPLAY INVISIBLE (-4675 3675);
FORCEPROP 1 LAST NEEDS_NO_SIZE TRUE
J 0
(-4675 3675);
DISPLAY 0.723404 (-4675 3675);
PAINT GREEN (-4675 3675);
DISPLAY INVISIBLE (-4675 3675);
FORCEPROP 1 LAST PATH I159
J 0
(-4675 3675);
DISPLAY 0.723404 (-4675 3675);
PAINT GREEN (-4675 3675);
DISPLAY INVISIBLE (-4675 3675);
FORCEADD OFFPAGE..3
(-2675 6075);
FORCEPROP 2 LAST $XR0 89 
J 0
(-2461 6075);
DISPLAY 0.638298 (-2461 6075);
PAINT MONO (-2461 6075);
FORCEPROP 2 LAST PATH I160
J 0
(-2450 6125);
DISPLAY 1.021277 (-2450 6125);
DISPLAY INVISIBLE (-2450 6125);
FORCEPROP 1 LAST COMMENT_BODY TRUE
J 0
(-2725 5975);
DISPLAY 0.872340 (-2725 5975);
PAINT GREEN (-2725 5975);
DISPLAY INVISIBLE (-2725 5975);
FORCEPROP 1 LAST OFFPAGE TRUE
J 0
(-2350 5950);
DISPLAY 0.872340 (-2350 5950);
PAINT GREEN (-2350 5950);
DISPLAY INVISIBLE (-2350 5950);
FORCEPROP 2 LAST CDS_LIB mstr_standard
J 0
(-2675 6075);
DISPLAY 0.723404 (-2675 6075);
PAINT MONO (-2675 6075);
DISPLAY INVISIBLE (-2675 6075);
FORCEADD OFFPAGE..3
(-2675 4275);
FORCEPROP 2 LAST $XR0 89 
J 0
(-2461 4275);
DISPLAY 0.638298 (-2461 4275);
PAINT MONO (-2461 4275);
FORCEPROP 2 LAST PATH I161
J 0
(-2450 4325);
DISPLAY 1.021277 (-2450 4325);
DISPLAY INVISIBLE (-2450 4325);
FORCEPROP 1 LAST COMMENT_BODY TRUE
J 0
(-2725 4175);
DISPLAY 0.872340 (-2725 4175);
PAINT GREEN (-2725 4175);
DISPLAY INVISIBLE (-2725 4175);
FORCEPROP 1 LAST OFFPAGE TRUE
J 0
(-2350 4150);
DISPLAY 0.872340 (-2350 4150);
PAINT GREEN (-2350 4150);
DISPLAY INVISIBLE (-2350 4150);
FORCEPROP 2 LAST CDS_LIB mstr_standard
J 0
(-2675 4275);
DISPLAY 0.723404 (-2675 4275);
PAINT MONO (-2675 4275);
DISPLAY INVISIBLE (-2675 4275);
FORCEADD TAP..1
(-3400 6050);
FORCEPROP 3 LASTPIN (-3450 6050) SIG_NAME M_E_CPU0_SA_DQ<0>
J 0
(-3440 6060);
DISPLAY 0.659574 (-3440 6060);
PAINT MONO (-3440 6060);
DISPLAY INVISIBLE (-3440 6060);
FORCEPROP 1 LASTPIN (-3450 6050) BN 0
J 0
(-3462 6058);
DISPLAY 0.489362 (-3462 6058);
PAINT GREEN (-3462 6058);
FORCEPROP 2 LAST CDS_LIB mstr_standard
J 0
(-3400 6050);
DISPLAY 0.723404 (-3400 6050);
PAINT MONO (-3400 6050);
DISPLAY INVISIBLE (-3400 6050);
FORCEPROP 1 LAST BODY_TYPE PLUMBING
J 0
(-3400 6100);
DISPLAY 0.872340 (-3400 6100);
PAINT GREEN (-3400 6100);
DISPLAY INVISIBLE (-3400 6100);
FORCEPROP 1 LAST HDL_TAP TRUE
J 0
(-3075 5925);
DISPLAY 0.872340 (-3075 5925);
DISPLAY INVISIBLE (-3075 5925);
FORCEPROP 1 LAST PATH I162
J 0
(-3402 6050);
DISPLAY 0.872340 (-3402 6050);
PAINT GREEN (-3402 6050);
DISPLAY INVISIBLE (-3402 6050);
FORCEADD TAP..1
(-3400 5900);
FORCEPROP 3 LASTPIN (-3450 5900) SIG_NAME M_E_CPU0_SA_DQ<3>
J 0
(-3440 5910);
DISPLAY 0.659574 (-3440 5910);
PAINT MONO (-3440 5910);
DISPLAY INVISIBLE (-3440 5910);
FORCEPROP 1 LASTPIN (-3450 5900) BN 3
J 0
(-3462 5908);
DISPLAY 0.489362 (-3462 5908);
PAINT GREEN (-3462 5908);
FORCEPROP 2 LAST CDS_LIB mstr_standard
J 0
(-3400 5900);
DISPLAY 0.723404 (-3400 5900);
PAINT MONO (-3400 5900);
DISPLAY INVISIBLE (-3400 5900);
FORCEPROP 1 LAST BODY_TYPE PLUMBING
J 0
(-3400 5950);
DISPLAY 0.872340 (-3400 5950);
PAINT GREEN (-3400 5950);
DISPLAY INVISIBLE (-3400 5950);
FORCEPROP 1 LAST HDL_TAP TRUE
J 0
(-3075 5775);
DISPLAY 0.872340 (-3075 5775);
DISPLAY INVISIBLE (-3075 5775);
FORCEPROP 1 LAST PATH I163
J 0
(-3402 5900);
DISPLAY 0.872340 (-3402 5900);
PAINT GREEN (-3402 5900);
DISPLAY INVISIBLE (-3402 5900);
FORCEADD TAP..1
(-3400 6000);
FORCEPROP 3 LASTPIN (-3450 6000) SIG_NAME M_E_CPU0_SA_DQ<1>
J 0
(-3440 6010);
DISPLAY 0.659574 (-3440 6010);
PAINT MONO (-3440 6010);
DISPLAY INVISIBLE (-3440 6010);
FORCEPROP 1 LASTPIN (-3450 6000) BN 1
J 0
(-3462 6008);
DISPLAY 0.489362 (-3462 6008);
PAINT GREEN (-3462 6008);
FORCEPROP 2 LAST CDS_LIB mstr_standard
J 0
(-3400 6000);
DISPLAY 0.723404 (-3400 6000);
PAINT MONO (-3400 6000);
DISPLAY INVISIBLE (-3400 6000);
FORCEPROP 1 LAST BODY_TYPE PLUMBING
J 0
(-3400 6050);
DISPLAY 0.872340 (-3400 6050);
PAINT GREEN (-3400 6050);
DISPLAY INVISIBLE (-3400 6050);
FORCEPROP 1 LAST HDL_TAP TRUE
J 0
(-3075 5875);
DISPLAY 0.872340 (-3075 5875);
DISPLAY INVISIBLE (-3075 5875);
FORCEPROP 1 LAST PATH I164
J 0
(-3402 6000);
DISPLAY 0.872340 (-3402 6000);
PAINT GREEN (-3402 6000);
DISPLAY INVISIBLE (-3402 6000);
FORCEADD TAP..1
(-3400 5950);
FORCEPROP 3 LASTPIN (-3450 5950) SIG_NAME M_E_CPU0_SA_DQ<2>
J 0
(-3440 5960);
DISPLAY 0.659574 (-3440 5960);
PAINT MONO (-3440 5960);
DISPLAY INVISIBLE (-3440 5960);
FORCEPROP 1 LASTPIN (-3450 5950) BN 2
J 0
(-3462 5958);
DISPLAY 0.489362 (-3462 5958);
PAINT GREEN (-3462 5958);
FORCEPROP 2 LAST CDS_LIB mstr_standard
J 0
(-3400 5950);
DISPLAY 0.723404 (-3400 5950);
PAINT MONO (-3400 5950);
DISPLAY INVISIBLE (-3400 5950);
FORCEPROP 1 LAST BODY_TYPE PLUMBING
J 0
(-3400 6000);
DISPLAY 0.872340 (-3400 6000);
PAINT GREEN (-3400 6000);
DISPLAY INVISIBLE (-3400 6000);
FORCEPROP 1 LAST HDL_TAP TRUE
J 0
(-3075 5825);
DISPLAY 0.872340 (-3075 5825);
DISPLAY INVISIBLE (-3075 5825);
FORCEPROP 1 LAST PATH I165
J 0
(-3402 5950);
DISPLAY 0.872340 (-3402 5950);
PAINT GREEN (-3402 5950);
DISPLAY INVISIBLE (-3402 5950);
FORCEADD TAP..1
(-3400 5800);
FORCEPROP 3 LASTPIN (-3450 5800) SIG_NAME M_E_CPU0_SA_DQ<5>
J 0
(-3440 5810);
DISPLAY 0.659574 (-3440 5810);
PAINT MONO (-3440 5810);
DISPLAY INVISIBLE (-3440 5810);
FORCEPROP 1 LASTPIN (-3450 5800) BN 5
J 0
(-3462 5808);
DISPLAY 0.489362 (-3462 5808);
PAINT GREEN (-3462 5808);
FORCEPROP 2 LAST CDS_LIB mstr_standard
J 0
(-3400 5800);
DISPLAY 0.723404 (-3400 5800);
PAINT MONO (-3400 5800);
DISPLAY INVISIBLE (-3400 5800);
FORCEPROP 1 LAST BODY_TYPE PLUMBING
J 0
(-3400 5850);
DISPLAY 0.872340 (-3400 5850);
PAINT GREEN (-3400 5850);
DISPLAY INVISIBLE (-3400 5850);
FORCEPROP 1 LAST HDL_TAP TRUE
J 0
(-3075 5675);
DISPLAY 0.872340 (-3075 5675);
DISPLAY INVISIBLE (-3075 5675);
FORCEPROP 1 LAST PATH I166
J 0
(-3402 5800);
DISPLAY 0.872340 (-3402 5800);
PAINT GREEN (-3402 5800);
DISPLAY INVISIBLE (-3402 5800);
FORCEADD TAP..1
(-3400 5850);
FORCEPROP 3 LASTPIN (-3450 5850) SIG_NAME M_E_CPU0_SA_DQ<4>
J 0
(-3440 5860);
DISPLAY 0.659574 (-3440 5860);
PAINT MONO (-3440 5860);
DISPLAY INVISIBLE (-3440 5860);
FORCEPROP 1 LASTPIN (-3450 5850) BN 4
J 0
(-3462 5858);
DISPLAY 0.489362 (-3462 5858);
PAINT GREEN (-3462 5858);
FORCEPROP 2 LAST CDS_LIB mstr_standard
J 0
(-3400 5850);
DISPLAY 0.723404 (-3400 5850);
PAINT MONO (-3400 5850);
DISPLAY INVISIBLE (-3400 5850);
FORCEPROP 1 LAST BODY_TYPE PLUMBING
J 0
(-3400 5900);
DISPLAY 0.872340 (-3400 5900);
PAINT GREEN (-3400 5900);
DISPLAY INVISIBLE (-3400 5900);
FORCEPROP 1 LAST HDL_TAP TRUE
J 0
(-3075 5725);
DISPLAY 0.872340 (-3075 5725);
DISPLAY INVISIBLE (-3075 5725);
FORCEPROP 1 LAST PATH I167
J 0
(-3402 5850);
DISPLAY 0.872340 (-3402 5850);
PAINT GREEN (-3402 5850);
DISPLAY INVISIBLE (-3402 5850);
FORCEADD TAP..1
(-3400 5750);
FORCEPROP 3 LASTPIN (-3450 5750) SIG_NAME M_E_CPU0_SA_DQ<6>
J 0
(-3440 5760);
DISPLAY 0.659574 (-3440 5760);
PAINT MONO (-3440 5760);
DISPLAY INVISIBLE (-3440 5760);
FORCEPROP 1 LASTPIN (-3450 5750) BN 6
J 0
(-3462 5758);
DISPLAY 0.489362 (-3462 5758);
PAINT GREEN (-3462 5758);
FORCEPROP 2 LAST CDS_LIB mstr_standard
J 0
(-3400 5750);
DISPLAY 0.723404 (-3400 5750);
PAINT MONO (-3400 5750);
DISPLAY INVISIBLE (-3400 5750);
FORCEPROP 1 LAST BODY_TYPE PLUMBING
J 0
(-3400 5800);
DISPLAY 0.872340 (-3400 5800);
PAINT GREEN (-3400 5800);
DISPLAY INVISIBLE (-3400 5800);
FORCEPROP 1 LAST HDL_TAP TRUE
J 0
(-3075 5625);
DISPLAY 0.872340 (-3075 5625);
DISPLAY INVISIBLE (-3075 5625);
FORCEPROP 1 LAST PATH I168
J 0
(-3402 5750);
DISPLAY 0.872340 (-3402 5750);
PAINT GREEN (-3402 5750);
DISPLAY INVISIBLE (-3402 5750);
FORCEADD TAP..1
(-3400 5700);
FORCEPROP 3 LASTPIN (-3450 5700) SIG_NAME M_E_CPU0_SA_DQ<7>
J 0
(-3440 5710);
DISPLAY 0.659574 (-3440 5710);
PAINT MONO (-3440 5710);
DISPLAY INVISIBLE (-3440 5710);
FORCEPROP 1 LASTPIN (-3450 5700) BN 7
J 0
(-3462 5708);
DISPLAY 0.489362 (-3462 5708);
PAINT GREEN (-3462 5708);
FORCEPROP 2 LAST CDS_LIB mstr_standard
J 0
(-3400 5700);
DISPLAY 0.723404 (-3400 5700);
PAINT MONO (-3400 5700);
DISPLAY INVISIBLE (-3400 5700);
FORCEPROP 1 LAST BODY_TYPE PLUMBING
J 0
(-3400 5750);
DISPLAY 0.872340 (-3400 5750);
PAINT GREEN (-3400 5750);
DISPLAY INVISIBLE (-3400 5750);
FORCEPROP 1 LAST HDL_TAP TRUE
J 0
(-3075 5575);
DISPLAY 0.872340 (-3075 5575);
DISPLAY INVISIBLE (-3075 5575);
FORCEPROP 1 LAST PATH I169
J 0
(-3402 5700);
DISPLAY 0.872340 (-3402 5700);
PAINT GREEN (-3402 5700);
DISPLAY INVISIBLE (-3402 5700);
FORCEADD TAP..1
(-3400 5550);
FORCEPROP 3 LASTPIN (-3450 5550) SIG_NAME M_E_CPU0_SA_DQ<9>
J 0
(-3440 5560);
DISPLAY 0.659574 (-3440 5560);
PAINT MONO (-3440 5560);
DISPLAY INVISIBLE (-3440 5560);
FORCEPROP 1 LASTPIN (-3450 5550) BN 9
J 0
(-3462 5558);
DISPLAY 0.489362 (-3462 5558);
PAINT GREEN (-3462 5558);
FORCEPROP 2 LAST CDS_LIB mstr_standard
J 0
(-3400 5550);
DISPLAY 0.723404 (-3400 5550);
PAINT MONO (-3400 5550);
DISPLAY INVISIBLE (-3400 5550);
FORCEPROP 1 LAST BODY_TYPE PLUMBING
J 0
(-3400 5600);
DISPLAY 0.872340 (-3400 5600);
PAINT GREEN (-3400 5600);
DISPLAY INVISIBLE (-3400 5600);
FORCEPROP 1 LAST HDL_TAP TRUE
J 0
(-3075 5425);
DISPLAY 0.872340 (-3075 5425);
DISPLAY INVISIBLE (-3075 5425);
FORCEPROP 1 LAST PATH I170
J 0
(-3402 5550);
DISPLAY 0.872340 (-3402 5550);
PAINT GREEN (-3402 5550);
DISPLAY INVISIBLE (-3402 5550);
FORCEADD TAP..1
(-3400 5600);
FORCEPROP 3 LASTPIN (-3450 5600) SIG_NAME M_E_CPU0_SA_DQ<8>
J 0
(-3440 5610);
DISPLAY 0.659574 (-3440 5610);
PAINT MONO (-3440 5610);
DISPLAY INVISIBLE (-3440 5610);
FORCEPROP 1 LASTPIN (-3450 5600) BN 8
J 0
(-3462 5608);
DISPLAY 0.489362 (-3462 5608);
PAINT GREEN (-3462 5608);
FORCEPROP 2 LAST CDS_LIB mstr_standard
J 0
(-3400 5600);
DISPLAY 0.723404 (-3400 5600);
PAINT MONO (-3400 5600);
DISPLAY INVISIBLE (-3400 5600);
FORCEPROP 1 LAST BODY_TYPE PLUMBING
J 0
(-3400 5650);
DISPLAY 0.872340 (-3400 5650);
PAINT GREEN (-3400 5650);
DISPLAY INVISIBLE (-3400 5650);
FORCEPROP 1 LAST HDL_TAP TRUE
J 0
(-3075 5475);
DISPLAY 0.872340 (-3075 5475);
DISPLAY INVISIBLE (-3075 5475);
FORCEPROP 1 LAST PATH I171
J 0
(-3402 5600);
DISPLAY 0.872340 (-3402 5600);
PAINT GREEN (-3402 5600);
DISPLAY INVISIBLE (-3402 5600);
FORCEADD TAP..1
(-3400 5400);
FORCEPROP 3 LASTPIN (-3450 5400) SIG_NAME M_E_CPU0_SA_DQ<12>
J 0
(-3440 5410);
DISPLAY 0.659574 (-3440 5410);
PAINT MONO (-3440 5410);
DISPLAY INVISIBLE (-3440 5410);
FORCEPROP 1 LASTPIN (-3450 5400) BN 12
J 0
(-3462 5408);
DISPLAY 0.489362 (-3462 5408);
PAINT GREEN (-3462 5408);
FORCEPROP 2 LAST CDS_LIB mstr_standard
J 0
(-3400 5400);
DISPLAY 0.723404 (-3400 5400);
PAINT MONO (-3400 5400);
DISPLAY INVISIBLE (-3400 5400);
FORCEPROP 1 LAST BODY_TYPE PLUMBING
J 0
(-3400 5450);
DISPLAY 0.872340 (-3400 5450);
PAINT GREEN (-3400 5450);
DISPLAY INVISIBLE (-3400 5450);
FORCEPROP 1 LAST HDL_TAP TRUE
J 0
(-3075 5275);
DISPLAY 0.872340 (-3075 5275);
DISPLAY INVISIBLE (-3075 5275);
FORCEPROP 1 LAST PATH I172
J 0
(-3402 5400);
DISPLAY 0.872340 (-3402 5400);
PAINT GREEN (-3402 5400);
DISPLAY INVISIBLE (-3402 5400);
FORCEADD TAP..1
(-3400 5450);
FORCEPROP 3 LASTPIN (-3450 5450) SIG_NAME M_E_CPU0_SA_DQ<11>
J 0
(-3440 5460);
DISPLAY 0.659574 (-3440 5460);
PAINT MONO (-3440 5460);
DISPLAY INVISIBLE (-3440 5460);
FORCEPROP 1 LASTPIN (-3450 5450) BN 11
J 0
(-3462 5458);
DISPLAY 0.489362 (-3462 5458);
PAINT GREEN (-3462 5458);
FORCEPROP 2 LAST CDS_LIB mstr_standard
J 0
(-3400 5450);
DISPLAY 0.723404 (-3400 5450);
PAINT MONO (-3400 5450);
DISPLAY INVISIBLE (-3400 5450);
FORCEPROP 1 LAST BODY_TYPE PLUMBING
J 0
(-3400 5500);
DISPLAY 0.872340 (-3400 5500);
PAINT GREEN (-3400 5500);
DISPLAY INVISIBLE (-3400 5500);
FORCEPROP 1 LAST HDL_TAP TRUE
J 0
(-3075 5325);
DISPLAY 0.872340 (-3075 5325);
DISPLAY INVISIBLE (-3075 5325);
FORCEPROP 1 LAST PATH I173
J 0
(-3402 5450);
DISPLAY 0.872340 (-3402 5450);
PAINT GREEN (-3402 5450);
DISPLAY INVISIBLE (-3402 5450);
FORCEADD TAP..1
(-3400 5500);
FORCEPROP 3 LASTPIN (-3450 5500) SIG_NAME M_E_CPU0_SA_DQ<10>
J 0
(-3440 5510);
DISPLAY 0.659574 (-3440 5510);
PAINT MONO (-3440 5510);
DISPLAY INVISIBLE (-3440 5510);
FORCEPROP 1 LASTPIN (-3450 5500) BN 10
J 0
(-3462 5508);
DISPLAY 0.489362 (-3462 5508);
PAINT GREEN (-3462 5508);
FORCEPROP 2 LAST CDS_LIB mstr_standard
J 0
(-3400 5500);
DISPLAY 0.723404 (-3400 5500);
PAINT MONO (-3400 5500);
DISPLAY INVISIBLE (-3400 5500);
FORCEPROP 1 LAST BODY_TYPE PLUMBING
J 0
(-3400 5550);
DISPLAY 0.872340 (-3400 5550);
PAINT GREEN (-3400 5550);
DISPLAY INVISIBLE (-3400 5550);
FORCEPROP 1 LAST HDL_TAP TRUE
J 0
(-3075 5375);
DISPLAY 0.872340 (-3075 5375);
DISPLAY INVISIBLE (-3075 5375);
FORCEPROP 1 LAST PATH I174
J 0
(-3402 5500);
DISPLAY 0.872340 (-3402 5500);
PAINT GREEN (-3402 5500);
DISPLAY INVISIBLE (-3402 5500);
FORCEADD TAP..1
(-3400 5250);
FORCEPROP 3 LASTPIN (-3450 5250) SIG_NAME M_E_CPU0_SA_DQ<15>
J 0
(-3440 5260);
DISPLAY 0.659574 (-3440 5260);
PAINT MONO (-3440 5260);
DISPLAY INVISIBLE (-3440 5260);
FORCEPROP 1 LASTPIN (-3450 5250) BN 15
J 0
(-3462 5258);
DISPLAY 0.489362 (-3462 5258);
PAINT GREEN (-3462 5258);
FORCEPROP 2 LAST CDS_LIB mstr_standard
J 0
(-3400 5250);
DISPLAY 0.723404 (-3400 5250);
PAINT MONO (-3400 5250);
DISPLAY INVISIBLE (-3400 5250);
FORCEPROP 1 LAST BODY_TYPE PLUMBING
J 0
(-3400 5300);
DISPLAY 0.872340 (-3400 5300);
PAINT GREEN (-3400 5300);
DISPLAY INVISIBLE (-3400 5300);
FORCEPROP 1 LAST HDL_TAP TRUE
J 0
(-3075 5125);
DISPLAY 0.872340 (-3075 5125);
DISPLAY INVISIBLE (-3075 5125);
FORCEPROP 1 LAST PATH I175
J 0
(-3402 5250);
DISPLAY 0.872340 (-3402 5250);
PAINT GREEN (-3402 5250);
DISPLAY INVISIBLE (-3402 5250);
FORCEADD TAP..1
(-3400 5300);
FORCEPROP 3 LASTPIN (-3450 5300) SIG_NAME M_E_CPU0_SA_DQ<14>
J 0
(-3440 5310);
DISPLAY 0.659574 (-3440 5310);
PAINT MONO (-3440 5310);
DISPLAY INVISIBLE (-3440 5310);
FORCEPROP 1 LASTPIN (-3450 5300) BN 14
J 0
(-3462 5308);
DISPLAY 0.489362 (-3462 5308);
PAINT GREEN (-3462 5308);
FORCEPROP 2 LAST CDS_LIB mstr_standard
J 0
(-3400 5300);
DISPLAY 0.723404 (-3400 5300);
PAINT MONO (-3400 5300);
DISPLAY INVISIBLE (-3400 5300);
FORCEPROP 1 LAST BODY_TYPE PLUMBING
J 0
(-3400 5350);
DISPLAY 0.872340 (-3400 5350);
PAINT GREEN (-3400 5350);
DISPLAY INVISIBLE (-3400 5350);
FORCEPROP 1 LAST HDL_TAP TRUE
J 0
(-3075 5175);
DISPLAY 0.872340 (-3075 5175);
DISPLAY INVISIBLE (-3075 5175);
FORCEPROP 1 LAST PATH I176
J 0
(-3402 5300);
DISPLAY 0.872340 (-3402 5300);
PAINT GREEN (-3402 5300);
DISPLAY INVISIBLE (-3402 5300);
FORCEADD TAP..1
(-3400 5350);
FORCEPROP 3 LASTPIN (-3450 5350) SIG_NAME M_E_CPU0_SA_DQ<13>
J 0
(-3440 5360);
DISPLAY 0.659574 (-3440 5360);
PAINT MONO (-3440 5360);
DISPLAY INVISIBLE (-3440 5360);
FORCEPROP 1 LASTPIN (-3450 5350) BN 13
J 0
(-3462 5358);
DISPLAY 0.489362 (-3462 5358);
PAINT GREEN (-3462 5358);
FORCEPROP 2 LAST CDS_LIB mstr_standard
J 0
(-3400 5350);
DISPLAY 0.723404 (-3400 5350);
PAINT MONO (-3400 5350);
DISPLAY INVISIBLE (-3400 5350);
FORCEPROP 1 LAST BODY_TYPE PLUMBING
J 0
(-3400 5400);
DISPLAY 0.872340 (-3400 5400);
PAINT GREEN (-3400 5400);
DISPLAY INVISIBLE (-3400 5400);
FORCEPROP 1 LAST HDL_TAP TRUE
J 0
(-3075 5225);
DISPLAY 0.872340 (-3075 5225);
DISPLAY INVISIBLE (-3075 5225);
FORCEPROP 1 LAST PATH I177
J 0
(-3402 5350);
DISPLAY 0.872340 (-3402 5350);
PAINT GREEN (-3402 5350);
DISPLAY INVISIBLE (-3402 5350);
FORCEADD TAP..1
(-3400 5150);
FORCEPROP 3 LASTPIN (-3450 5150) SIG_NAME M_E_CPU0_SA_DQ<16>
J 0
(-3440 5160);
DISPLAY 0.659574 (-3440 5160);
PAINT MONO (-3440 5160);
DISPLAY INVISIBLE (-3440 5160);
FORCEPROP 1 LASTPIN (-3450 5150) BN 16
J 0
(-3462 5158);
DISPLAY 0.489362 (-3462 5158);
PAINT GREEN (-3462 5158);
FORCEPROP 2 LAST CDS_LIB mstr_standard
J 0
(-3400 5150);
DISPLAY 0.723404 (-3400 5150);
PAINT MONO (-3400 5150);
DISPLAY INVISIBLE (-3400 5150);
FORCEPROP 1 LAST BODY_TYPE PLUMBING
J 0
(-3400 5200);
DISPLAY 0.872340 (-3400 5200);
PAINT GREEN (-3400 5200);
DISPLAY INVISIBLE (-3400 5200);
FORCEPROP 1 LAST HDL_TAP TRUE
J 0
(-3075 5025);
DISPLAY 0.872340 (-3075 5025);
DISPLAY INVISIBLE (-3075 5025);
FORCEPROP 1 LAST PATH I178
J 0
(-3402 5150);
DISPLAY 0.872340 (-3402 5150);
PAINT GREEN (-3402 5150);
DISPLAY INVISIBLE (-3402 5150);
FORCEADD TAP..1
(-3400 5050);
FORCEPROP 3 LASTPIN (-3450 5050) SIG_NAME M_E_CPU0_SA_DQ<18>
J 0
(-3440 5060);
DISPLAY 0.659574 (-3440 5060);
PAINT MONO (-3440 5060);
DISPLAY INVISIBLE (-3440 5060);
FORCEPROP 1 LASTPIN (-3450 5050) BN 18
J 0
(-3462 5058);
DISPLAY 0.489362 (-3462 5058);
PAINT GREEN (-3462 5058);
FORCEPROP 2 LAST CDS_LIB mstr_standard
J 0
(-3400 5050);
DISPLAY 0.723404 (-3400 5050);
PAINT MONO (-3400 5050);
DISPLAY INVISIBLE (-3400 5050);
FORCEPROP 1 LAST BODY_TYPE PLUMBING
J 0
(-3400 5100);
DISPLAY 0.872340 (-3400 5100);
PAINT GREEN (-3400 5100);
DISPLAY INVISIBLE (-3400 5100);
FORCEPROP 1 LAST HDL_TAP TRUE
J 0
(-3075 4925);
DISPLAY 0.872340 (-3075 4925);
DISPLAY INVISIBLE (-3075 4925);
FORCEPROP 1 LAST PATH I179
J 0
(-3402 5050);
DISPLAY 0.872340 (-3402 5050);
PAINT GREEN (-3402 5050);
DISPLAY INVISIBLE (-3402 5050);
FORCEADD TAP..1
(-3400 5100);
FORCEPROP 3 LASTPIN (-3450 5100) SIG_NAME M_E_CPU0_SA_DQ<17>
J 0
(-3440 5110);
DISPLAY 0.659574 (-3440 5110);
PAINT MONO (-3440 5110);
DISPLAY INVISIBLE (-3440 5110);
FORCEPROP 1 LASTPIN (-3450 5100) BN 17
J 0
(-3462 5108);
DISPLAY 0.489362 (-3462 5108);
PAINT GREEN (-3462 5108);
FORCEPROP 2 LAST CDS_LIB mstr_standard
J 0
(-3400 5100);
DISPLAY 0.723404 (-3400 5100);
PAINT MONO (-3400 5100);
DISPLAY INVISIBLE (-3400 5100);
FORCEPROP 1 LAST BODY_TYPE PLUMBING
J 0
(-3400 5150);
DISPLAY 0.872340 (-3400 5150);
PAINT GREEN (-3400 5150);
DISPLAY INVISIBLE (-3400 5150);
FORCEPROP 1 LAST HDL_TAP TRUE
J 0
(-3075 4975);
DISPLAY 0.872340 (-3075 4975);
DISPLAY INVISIBLE (-3075 4975);
FORCEPROP 1 LAST PATH I180
J 0
(-3402 5100);
DISPLAY 0.872340 (-3402 5100);
PAINT GREEN (-3402 5100);
DISPLAY INVISIBLE (-3402 5100);
FORCEADD TAP..1
(-3400 5000);
FORCEPROP 3 LASTPIN (-3450 5000) SIG_NAME M_E_CPU0_SA_DQ<19>
J 0
(-3440 5010);
DISPLAY 0.659574 (-3440 5010);
PAINT MONO (-3440 5010);
DISPLAY INVISIBLE (-3440 5010);
FORCEPROP 1 LASTPIN (-3450 5000) BN 19
J 0
(-3462 5008);
DISPLAY 0.489362 (-3462 5008);
PAINT GREEN (-3462 5008);
FORCEPROP 2 LAST CDS_LIB mstr_standard
J 0
(-3400 5000);
DISPLAY 0.723404 (-3400 5000);
PAINT MONO (-3400 5000);
DISPLAY INVISIBLE (-3400 5000);
FORCEPROP 1 LAST BODY_TYPE PLUMBING
J 0
(-3400 5050);
DISPLAY 0.872340 (-3400 5050);
PAINT GREEN (-3400 5050);
DISPLAY INVISIBLE (-3400 5050);
FORCEPROP 1 LAST HDL_TAP TRUE
J 0
(-3075 4875);
DISPLAY 0.872340 (-3075 4875);
DISPLAY INVISIBLE (-3075 4875);
FORCEPROP 1 LAST PATH I181
J 0
(-3402 5000);
DISPLAY 0.872340 (-3402 5000);
PAINT GREEN (-3402 5000);
DISPLAY INVISIBLE (-3402 5000);
FORCEADD TAP..1
(-3400 4950);
FORCEPROP 3 LASTPIN (-3450 4950) SIG_NAME M_E_CPU0_SA_DQ<20>
J 0
(-3440 4960);
DISPLAY 0.659574 (-3440 4960);
PAINT MONO (-3440 4960);
DISPLAY INVISIBLE (-3440 4960);
FORCEPROP 1 LASTPIN (-3450 4950) BN 20
J 0
(-3462 4958);
DISPLAY 0.489362 (-3462 4958);
PAINT GREEN (-3462 4958);
FORCEPROP 2 LAST CDS_LIB mstr_standard
J 0
(-3400 4950);
DISPLAY 0.723404 (-3400 4950);
PAINT MONO (-3400 4950);
DISPLAY INVISIBLE (-3400 4950);
FORCEPROP 1 LAST BODY_TYPE PLUMBING
J 0
(-3400 5000);
DISPLAY 0.872340 (-3400 5000);
PAINT GREEN (-3400 5000);
DISPLAY INVISIBLE (-3400 5000);
FORCEPROP 1 LAST HDL_TAP TRUE
J 0
(-3075 4825);
DISPLAY 0.872340 (-3075 4825);
DISPLAY INVISIBLE (-3075 4825);
FORCEPROP 1 LAST PATH I182
J 0
(-3402 4950);
DISPLAY 0.872340 (-3402 4950);
PAINT GREEN (-3402 4950);
DISPLAY INVISIBLE (-3402 4950);
FORCEADD TAP..1
(-3400 4900);
FORCEPROP 3 LASTPIN (-3450 4900) SIG_NAME M_E_CPU0_SA_DQ<21>
J 0
(-3440 4910);
DISPLAY 0.659574 (-3440 4910);
PAINT MONO (-3440 4910);
DISPLAY INVISIBLE (-3440 4910);
FORCEPROP 1 LASTPIN (-3450 4900) BN 21
J 0
(-3462 4908);
DISPLAY 0.489362 (-3462 4908);
PAINT GREEN (-3462 4908);
FORCEPROP 2 LAST CDS_LIB mstr_standard
J 0
(-3400 4900);
DISPLAY 0.723404 (-3400 4900);
PAINT MONO (-3400 4900);
DISPLAY INVISIBLE (-3400 4900);
FORCEPROP 1 LAST BODY_TYPE PLUMBING
J 0
(-3400 4950);
DISPLAY 0.872340 (-3400 4950);
PAINT GREEN (-3400 4950);
DISPLAY INVISIBLE (-3400 4950);
FORCEPROP 1 LAST HDL_TAP TRUE
J 0
(-3075 4775);
DISPLAY 0.872340 (-3075 4775);
DISPLAY INVISIBLE (-3075 4775);
FORCEPROP 1 LAST PATH I183
J 0
(-3402 4900);
DISPLAY 0.872340 (-3402 4900);
PAINT GREEN (-3402 4900);
DISPLAY INVISIBLE (-3402 4900);
FORCEADD TAP..1
(-3400 4800);
FORCEPROP 3 LASTPIN (-3450 4800) SIG_NAME M_E_CPU0_SA_DQ<23>
J 0
(-3440 4810);
DISPLAY 0.659574 (-3440 4810);
PAINT MONO (-3440 4810);
DISPLAY INVISIBLE (-3440 4810);
FORCEPROP 1 LASTPIN (-3450 4800) BN 23
J 0
(-3462 4808);
DISPLAY 0.489362 (-3462 4808);
PAINT GREEN (-3462 4808);
FORCEPROP 2 LAST CDS_LIB mstr_standard
J 0
(-3400 4800);
DISPLAY 0.723404 (-3400 4800);
PAINT MONO (-3400 4800);
DISPLAY INVISIBLE (-3400 4800);
FORCEPROP 1 LAST BODY_TYPE PLUMBING
J 0
(-3400 4850);
DISPLAY 0.872340 (-3400 4850);
PAINT GREEN (-3400 4850);
DISPLAY INVISIBLE (-3400 4850);
FORCEPROP 1 LAST HDL_TAP TRUE
J 0
(-3075 4675);
DISPLAY 0.872340 (-3075 4675);
DISPLAY INVISIBLE (-3075 4675);
FORCEPROP 1 LAST PATH I184
J 0
(-3402 4800);
DISPLAY 0.872340 (-3402 4800);
PAINT GREEN (-3402 4800);
DISPLAY INVISIBLE (-3402 4800);
FORCEADD TAP..1
(-3400 4850);
FORCEPROP 3 LASTPIN (-3450 4850) SIG_NAME M_E_CPU0_SA_DQ<22>
J 0
(-3440 4860);
DISPLAY 0.659574 (-3440 4860);
PAINT MONO (-3440 4860);
DISPLAY INVISIBLE (-3440 4860);
FORCEPROP 1 LASTPIN (-3450 4850) BN 22
J 0
(-3462 4858);
DISPLAY 0.489362 (-3462 4858);
PAINT GREEN (-3462 4858);
FORCEPROP 2 LAST CDS_LIB mstr_standard
J 0
(-3400 4850);
DISPLAY 0.723404 (-3400 4850);
PAINT MONO (-3400 4850);
DISPLAY INVISIBLE (-3400 4850);
FORCEPROP 1 LAST BODY_TYPE PLUMBING
J 0
(-3400 4900);
DISPLAY 0.872340 (-3400 4900);
PAINT GREEN (-3400 4900);
DISPLAY INVISIBLE (-3400 4900);
FORCEPROP 1 LAST HDL_TAP TRUE
J 0
(-3075 4725);
DISPLAY 0.872340 (-3075 4725);
DISPLAY INVISIBLE (-3075 4725);
FORCEPROP 1 LAST PATH I185
J 0
(-3402 4850);
DISPLAY 0.872340 (-3402 4850);
PAINT GREEN (-3402 4850);
DISPLAY INVISIBLE (-3402 4850);
FORCEADD TAP..1
(-3400 4650);
FORCEPROP 3 LASTPIN (-3450 4650) SIG_NAME M_E_CPU0_SA_DQ<25>
J 0
(-3440 4660);
DISPLAY 0.659574 (-3440 4660);
PAINT MONO (-3440 4660);
DISPLAY INVISIBLE (-3440 4660);
FORCEPROP 1 LASTPIN (-3450 4650) BN 25
J 0
(-3462 4658);
DISPLAY 0.489362 (-3462 4658);
PAINT GREEN (-3462 4658);
FORCEPROP 2 LAST CDS_LIB mstr_standard
J 0
(-3400 4650);
DISPLAY 0.723404 (-3400 4650);
PAINT MONO (-3400 4650);
DISPLAY INVISIBLE (-3400 4650);
FORCEPROP 1 LAST BODY_TYPE PLUMBING
J 0
(-3400 4700);
DISPLAY 0.872340 (-3400 4700);
PAINT GREEN (-3400 4700);
DISPLAY INVISIBLE (-3400 4700);
FORCEPROP 1 LAST HDL_TAP TRUE
J 0
(-3075 4525);
DISPLAY 0.872340 (-3075 4525);
DISPLAY INVISIBLE (-3075 4525);
FORCEPROP 1 LAST PATH I186
J 0
(-3402 4650);
DISPLAY 0.872340 (-3402 4650);
PAINT GREEN (-3402 4650);
DISPLAY INVISIBLE (-3402 4650);
FORCEADD TAP..1
(-3400 4700);
FORCEPROP 3 LASTPIN (-3450 4700) SIG_NAME M_E_CPU0_SA_DQ<24>
J 0
(-3440 4710);
DISPLAY 0.659574 (-3440 4710);
PAINT MONO (-3440 4710);
DISPLAY INVISIBLE (-3440 4710);
FORCEPROP 1 LASTPIN (-3450 4700) BN 24
J 0
(-3462 4708);
DISPLAY 0.489362 (-3462 4708);
PAINT GREEN (-3462 4708);
FORCEPROP 2 LAST CDS_LIB mstr_standard
J 0
(-3400 4700);
DISPLAY 0.723404 (-3400 4700);
PAINT MONO (-3400 4700);
DISPLAY INVISIBLE (-3400 4700);
FORCEPROP 1 LAST BODY_TYPE PLUMBING
J 0
(-3400 4750);
DISPLAY 0.872340 (-3400 4750);
PAINT GREEN (-3400 4750);
DISPLAY INVISIBLE (-3400 4750);
FORCEPROP 1 LAST HDL_TAP TRUE
J 0
(-3075 4575);
DISPLAY 0.872340 (-3075 4575);
DISPLAY INVISIBLE (-3075 4575);
FORCEPROP 1 LAST PATH I187
J 0
(-3402 4700);
DISPLAY 0.872340 (-3402 4700);
PAINT GREEN (-3402 4700);
DISPLAY INVISIBLE (-3402 4700);
FORCEADD TAP..1
(-3400 4600);
FORCEPROP 3 LASTPIN (-3450 4600) SIG_NAME M_E_CPU0_SA_DQ<26>
J 0
(-3440 4610);
DISPLAY 0.659574 (-3440 4610);
PAINT MONO (-3440 4610);
DISPLAY INVISIBLE (-3440 4610);
FORCEPROP 1 LASTPIN (-3450 4600) BN 26
J 0
(-3462 4608);
DISPLAY 0.489362 (-3462 4608);
PAINT GREEN (-3462 4608);
FORCEPROP 2 LAST CDS_LIB mstr_standard
J 0
(-3400 4600);
DISPLAY 0.723404 (-3400 4600);
PAINT MONO (-3400 4600);
DISPLAY INVISIBLE (-3400 4600);
FORCEPROP 1 LAST BODY_TYPE PLUMBING
J 0
(-3400 4650);
DISPLAY 0.872340 (-3400 4650);
PAINT GREEN (-3400 4650);
DISPLAY INVISIBLE (-3400 4650);
FORCEPROP 1 LAST HDL_TAP TRUE
J 0
(-3075 4475);
DISPLAY 0.872340 (-3075 4475);
DISPLAY INVISIBLE (-3075 4475);
FORCEPROP 1 LAST PATH I188
J 0
(-3402 4600);
DISPLAY 0.872340 (-3402 4600);
PAINT GREEN (-3402 4600);
DISPLAY INVISIBLE (-3402 4600);
FORCEADD TAP..1
(-3400 4550);
FORCEPROP 3 LASTPIN (-3450 4550) SIG_NAME M_E_CPU0_SA_DQ<27>
J 0
(-3440 4560);
DISPLAY 0.659574 (-3440 4560);
PAINT MONO (-3440 4560);
DISPLAY INVISIBLE (-3440 4560);
FORCEPROP 1 LASTPIN (-3450 4550) BN 27
J 0
(-3462 4558);
DISPLAY 0.489362 (-3462 4558);
PAINT GREEN (-3462 4558);
FORCEPROP 2 LAST CDS_LIB mstr_standard
J 0
(-3400 4550);
DISPLAY 0.723404 (-3400 4550);
PAINT MONO (-3400 4550);
DISPLAY INVISIBLE (-3400 4550);
FORCEPROP 1 LAST BODY_TYPE PLUMBING
J 0
(-3400 4600);
DISPLAY 0.872340 (-3400 4600);
PAINT GREEN (-3400 4600);
DISPLAY INVISIBLE (-3400 4600);
FORCEPROP 1 LAST HDL_TAP TRUE
J 0
(-3075 4425);
DISPLAY 0.872340 (-3075 4425);
DISPLAY INVISIBLE (-3075 4425);
FORCEPROP 1 LAST PATH I189
J 0
(-3402 4550);
DISPLAY 0.872340 (-3402 4550);
PAINT GREEN (-3402 4550);
DISPLAY INVISIBLE (-3402 4550);
FORCEADD TAP..1
(-3400 4500);
FORCEPROP 3 LASTPIN (-3450 4500) SIG_NAME M_E_CPU0_SA_DQ<28>
J 0
(-3440 4510);
DISPLAY 0.659574 (-3440 4510);
PAINT MONO (-3440 4510);
DISPLAY INVISIBLE (-3440 4510);
FORCEPROP 1 LASTPIN (-3450 4500) BN 28
J 0
(-3462 4508);
DISPLAY 0.489362 (-3462 4508);
PAINT GREEN (-3462 4508);
FORCEPROP 2 LAST CDS_LIB mstr_standard
J 0
(-3400 4500);
DISPLAY 0.723404 (-3400 4500);
PAINT MONO (-3400 4500);
DISPLAY INVISIBLE (-3400 4500);
FORCEPROP 1 LAST BODY_TYPE PLUMBING
J 0
(-3400 4550);
DISPLAY 0.872340 (-3400 4550);
PAINT GREEN (-3400 4550);
DISPLAY INVISIBLE (-3400 4550);
FORCEPROP 1 LAST HDL_TAP TRUE
J 0
(-3075 4375);
DISPLAY 0.872340 (-3075 4375);
DISPLAY INVISIBLE (-3075 4375);
FORCEPROP 1 LAST PATH I190
J 0
(-3402 4500);
DISPLAY 0.872340 (-3402 4500);
PAINT GREEN (-3402 4500);
DISPLAY INVISIBLE (-3402 4500);
FORCEADD TAP..1
(-3400 4450);
FORCEPROP 3 LASTPIN (-3450 4450) SIG_NAME M_E_CPU0_SA_DQ<29>
J 0
(-3440 4460);
DISPLAY 0.659574 (-3440 4460);
PAINT MONO (-3440 4460);
DISPLAY INVISIBLE (-3440 4460);
FORCEPROP 1 LASTPIN (-3450 4450) BN 29
J 0
(-3462 4458);
DISPLAY 0.489362 (-3462 4458);
PAINT GREEN (-3462 4458);
FORCEPROP 2 LAST CDS_LIB mstr_standard
J 0
(-3400 4450);
DISPLAY 0.723404 (-3400 4450);
PAINT MONO (-3400 4450);
DISPLAY INVISIBLE (-3400 4450);
FORCEPROP 1 LAST BODY_TYPE PLUMBING
J 0
(-3400 4500);
DISPLAY 0.872340 (-3400 4500);
PAINT GREEN (-3400 4500);
DISPLAY INVISIBLE (-3400 4500);
FORCEPROP 1 LAST HDL_TAP TRUE
J 0
(-3075 4325);
DISPLAY 0.872340 (-3075 4325);
DISPLAY INVISIBLE (-3075 4325);
FORCEPROP 1 LAST PATH I191
J 0
(-3402 4450);
DISPLAY 0.872340 (-3402 4450);
PAINT GREEN (-3402 4450);
DISPLAY INVISIBLE (-3402 4450);
FORCEADD TAP..1
(-3400 4400);
FORCEPROP 3 LASTPIN (-3450 4400) SIG_NAME M_E_CPU0_SA_DQ<30>
J 0
(-3440 4410);
DISPLAY 0.659574 (-3440 4410);
PAINT MONO (-3440 4410);
DISPLAY INVISIBLE (-3440 4410);
FORCEPROP 1 LASTPIN (-3450 4400) BN 30
J 0
(-3462 4408);
DISPLAY 0.489362 (-3462 4408);
PAINT GREEN (-3462 4408);
FORCEPROP 2 LAST CDS_LIB mstr_standard
J 0
(-3400 4400);
DISPLAY 0.723404 (-3400 4400);
PAINT MONO (-3400 4400);
DISPLAY INVISIBLE (-3400 4400);
FORCEPROP 1 LAST BODY_TYPE PLUMBING
J 0
(-3400 4450);
DISPLAY 0.872340 (-3400 4450);
PAINT GREEN (-3400 4450);
DISPLAY INVISIBLE (-3400 4450);
FORCEPROP 1 LAST HDL_TAP TRUE
J 0
(-3075 4275);
DISPLAY 0.872340 (-3075 4275);
DISPLAY INVISIBLE (-3075 4275);
FORCEPROP 1 LAST PATH I192
J 0
(-3402 4400);
DISPLAY 0.872340 (-3402 4400);
PAINT GREEN (-3402 4400);
DISPLAY INVISIBLE (-3402 4400);
FORCEADD TAP..1
(-3400 4350);
FORCEPROP 3 LASTPIN (-3450 4350) SIG_NAME M_E_CPU0_SA_DQ<31>
J 0
(-3440 4360);
DISPLAY 0.659574 (-3440 4360);
PAINT MONO (-3440 4360);
DISPLAY INVISIBLE (-3440 4360);
FORCEPROP 1 LASTPIN (-3450 4350) BN 31
J 0
(-3462 4358);
DISPLAY 0.489362 (-3462 4358);
PAINT GREEN (-3462 4358);
FORCEPROP 2 LAST CDS_LIB mstr_standard
J 0
(-3400 4350);
DISPLAY 0.723404 (-3400 4350);
PAINT MONO (-3400 4350);
DISPLAY INVISIBLE (-3400 4350);
FORCEPROP 1 LAST BODY_TYPE PLUMBING
J 0
(-3400 4400);
DISPLAY 0.872340 (-3400 4400);
PAINT GREEN (-3400 4400);
DISPLAY INVISIBLE (-3400 4400);
FORCEPROP 1 LAST HDL_TAP TRUE
J 0
(-3075 4225);
DISPLAY 0.872340 (-3075 4225);
DISPLAY INVISIBLE (-3075 4225);
FORCEPROP 1 LAST PATH I193
J 0
(-3402 4350);
DISPLAY 0.872340 (-3402 4350);
PAINT GREEN (-3402 4350);
DISPLAY INVISIBLE (-3402 4350);
FORCEADD TAP..1
(-3400 4250);
FORCEPROP 3 LASTPIN (-3450 4250) SIG_NAME M_E_CPU0_SB_DQ<0>
J 0
(-3440 4260);
DISPLAY 0.659574 (-3440 4260);
PAINT MONO (-3440 4260);
DISPLAY INVISIBLE (-3440 4260);
FORCEPROP 1 LASTPIN (-3450 4250) BN 0
J 0
(-3462 4258);
DISPLAY 0.489362 (-3462 4258);
PAINT GREEN (-3462 4258);
FORCEPROP 2 LAST CDS_LIB mstr_standard
J 0
(-3400 4250);
DISPLAY 0.723404 (-3400 4250);
PAINT MONO (-3400 4250);
DISPLAY INVISIBLE (-3400 4250);
FORCEPROP 1 LAST BODY_TYPE PLUMBING
J 0
(-3400 4300);
DISPLAY 0.872340 (-3400 4300);
PAINT GREEN (-3400 4300);
DISPLAY INVISIBLE (-3400 4300);
FORCEPROP 1 LAST HDL_TAP TRUE
J 0
(-3075 4125);
DISPLAY 0.872340 (-3075 4125);
DISPLAY INVISIBLE (-3075 4125);
FORCEPROP 1 LAST PATH I194
J 0
(-3402 4250);
DISPLAY 0.872340 (-3402 4250);
PAINT GREEN (-3402 4250);
DISPLAY INVISIBLE (-3402 4250);
FORCEADD TAP..1
(-3400 4100);
FORCEPROP 3 LASTPIN (-3450 4100) SIG_NAME M_E_CPU0_SB_DQ<3>
J 0
(-3440 4110);
DISPLAY 0.659574 (-3440 4110);
PAINT MONO (-3440 4110);
DISPLAY INVISIBLE (-3440 4110);
FORCEPROP 1 LASTPIN (-3450 4100) BN 3
J 0
(-3462 4108);
DISPLAY 0.489362 (-3462 4108);
PAINT GREEN (-3462 4108);
FORCEPROP 2 LAST CDS_LIB mstr_standard
J 0
(-3400 4100);
DISPLAY 0.723404 (-3400 4100);
PAINT MONO (-3400 4100);
DISPLAY INVISIBLE (-3400 4100);
FORCEPROP 1 LAST BODY_TYPE PLUMBING
J 0
(-3400 4150);
DISPLAY 0.872340 (-3400 4150);
PAINT GREEN (-3400 4150);
DISPLAY INVISIBLE (-3400 4150);
FORCEPROP 1 LAST HDL_TAP TRUE
J 0
(-3075 3975);
DISPLAY 0.872340 (-3075 3975);
DISPLAY INVISIBLE (-3075 3975);
FORCEPROP 1 LAST PATH I195
J 0
(-3402 4100);
DISPLAY 0.872340 (-3402 4100);
PAINT GREEN (-3402 4100);
DISPLAY INVISIBLE (-3402 4100);
FORCEADD TAP..1
(-3400 4200);
FORCEPROP 3 LASTPIN (-3450 4200) SIG_NAME M_E_CPU0_SB_DQ<1>
J 0
(-3440 4210);
DISPLAY 0.659574 (-3440 4210);
PAINT MONO (-3440 4210);
DISPLAY INVISIBLE (-3440 4210);
FORCEPROP 1 LASTPIN (-3450 4200) BN 1
J 0
(-3462 4208);
DISPLAY 0.489362 (-3462 4208);
PAINT GREEN (-3462 4208);
FORCEPROP 2 LAST CDS_LIB mstr_standard
J 0
(-3400 4200);
DISPLAY 0.723404 (-3400 4200);
PAINT MONO (-3400 4200);
DISPLAY INVISIBLE (-3400 4200);
FORCEPROP 1 LAST BODY_TYPE PLUMBING
J 0
(-3400 4250);
DISPLAY 0.872340 (-3400 4250);
PAINT GREEN (-3400 4250);
DISPLAY INVISIBLE (-3400 4250);
FORCEPROP 1 LAST HDL_TAP TRUE
J 0
(-3075 4075);
DISPLAY 0.872340 (-3075 4075);
DISPLAY INVISIBLE (-3075 4075);
FORCEPROP 1 LAST PATH I196
J 0
(-3402 4200);
DISPLAY 0.872340 (-3402 4200);
PAINT GREEN (-3402 4200);
DISPLAY INVISIBLE (-3402 4200);
FORCEADD TAP..1
(-3400 4150);
FORCEPROP 3 LASTPIN (-3450 4150) SIG_NAME M_E_CPU0_SB_DQ<2>
J 0
(-3440 4160);
DISPLAY 0.659574 (-3440 4160);
PAINT MONO (-3440 4160);
DISPLAY INVISIBLE (-3440 4160);
FORCEPROP 1 LASTPIN (-3450 4150) BN 2
J 0
(-3462 4158);
DISPLAY 0.489362 (-3462 4158);
PAINT GREEN (-3462 4158);
FORCEPROP 2 LAST CDS_LIB mstr_standard
J 0
(-3400 4150);
DISPLAY 0.723404 (-3400 4150);
PAINT MONO (-3400 4150);
DISPLAY INVISIBLE (-3400 4150);
FORCEPROP 1 LAST BODY_TYPE PLUMBING
J 0
(-3400 4200);
DISPLAY 0.872340 (-3400 4200);
PAINT GREEN (-3400 4200);
DISPLAY INVISIBLE (-3400 4200);
FORCEPROP 1 LAST HDL_TAP TRUE
J 0
(-3075 4025);
DISPLAY 0.872340 (-3075 4025);
DISPLAY INVISIBLE (-3075 4025);
FORCEPROP 1 LAST PATH I197
J 0
(-3402 4150);
DISPLAY 0.872340 (-3402 4150);
PAINT GREEN (-3402 4150);
DISPLAY INVISIBLE (-3402 4150);
FORCEADD OFFPAGE..6
R 2
(-2800 2500);
FORCEPROP 2 LAST $XR0 89 
J 0
(-2586 2500);
DISPLAY 0.638298 (-2586 2500);
PAINT MONO (-2586 2500);
FORCEPROP 2 LAST PATH I198
J 0
(-2575 2550);
DISPLAY 1.021277 (-2575 2550);
DISPLAY INVISIBLE (-2575 2550);
FORCEPROP 1 LAST COMMENT_BODY TRUE
J 2
(-2900 2425);
DISPLAY 0.872340 (-2900 2425);
PAINT GREEN (-2900 2425);
DISPLAY INVISIBLE (-2900 2425);
FORCEPROP 1 LAST OFFPAGE TRUE
J 2
(-3125 2375);
DISPLAY 0.872340 (-3125 2375);
PAINT GREEN (-3125 2375);
DISPLAY INVISIBLE (-3125 2375);
FORCEPROP 2 LAST CDS_LIB mstr_standard
J 2
(-2800 2500);
DISPLAY 0.723404 (-2800 2500);
PAINT MONO (-2800 2500);
DISPLAY INVISIBLE (-2800 2500);
FORCEADD TAP..1
(-3400 4000);
FORCEPROP 3 LASTPIN (-3450 4000) SIG_NAME M_E_CPU0_SB_DQ<5>
J 0
(-3440 4010);
DISPLAY 0.659574 (-3440 4010);
PAINT MONO (-3440 4010);
DISPLAY INVISIBLE (-3440 4010);
FORCEPROP 1 LASTPIN (-3450 4000) BN 5
J 0
(-3462 4008);
DISPLAY 0.489362 (-3462 4008);
PAINT GREEN (-3462 4008);
FORCEPROP 2 LAST CDS_LIB mstr_standard
J 0
(-3400 4000);
DISPLAY 0.723404 (-3400 4000);
PAINT MONO (-3400 4000);
DISPLAY INVISIBLE (-3400 4000);
FORCEPROP 1 LAST BODY_TYPE PLUMBING
J 0
(-3400 4050);
DISPLAY 0.872340 (-3400 4050);
PAINT GREEN (-3400 4050);
DISPLAY INVISIBLE (-3400 4050);
FORCEPROP 1 LAST HDL_TAP TRUE
J 0
(-3075 3875);
DISPLAY 0.872340 (-3075 3875);
DISPLAY INVISIBLE (-3075 3875);
FORCEPROP 1 LAST PATH I199
J 0
(-3402 4000);
DISPLAY 0.872340 (-3402 4000);
PAINT GREEN (-3402 4000);
DISPLAY INVISIBLE (-3402 4000);
FORCEADD TAP..1
(-3400 4050);
FORCEPROP 3 LASTPIN (-3450 4050) SIG_NAME M_E_CPU0_SB_DQ<4>
J 0
(-3440 4060);
DISPLAY 0.659574 (-3440 4060);
PAINT MONO (-3440 4060);
DISPLAY INVISIBLE (-3440 4060);
FORCEPROP 1 LASTPIN (-3450 4050) BN 4
J 0
(-3462 4058);
DISPLAY 0.489362 (-3462 4058);
PAINT GREEN (-3462 4058);
FORCEPROP 2 LAST CDS_LIB mstr_standard
J 0
(-3400 4050);
DISPLAY 0.723404 (-3400 4050);
PAINT MONO (-3400 4050);
DISPLAY INVISIBLE (-3400 4050);
FORCEPROP 1 LAST BODY_TYPE PLUMBING
J 0
(-3400 4100);
DISPLAY 0.872340 (-3400 4100);
PAINT GREEN (-3400 4100);
DISPLAY INVISIBLE (-3400 4100);
FORCEPROP 1 LAST HDL_TAP TRUE
J 0
(-3075 3925);
DISPLAY 0.872340 (-3075 3925);
DISPLAY INVISIBLE (-3075 3925);
FORCEPROP 1 LAST PATH I200
J 0
(-3402 4050);
DISPLAY 0.872340 (-3402 4050);
PAINT GREEN (-3402 4050);
DISPLAY INVISIBLE (-3402 4050);
FORCEADD TAP..1
(-3400 3950);
FORCEPROP 3 LASTPIN (-3450 3950) SIG_NAME M_E_CPU0_SB_DQ<6>
J 0
(-3440 3960);
DISPLAY 0.659574 (-3440 3960);
PAINT MONO (-3440 3960);
DISPLAY INVISIBLE (-3440 3960);
FORCEPROP 1 LASTPIN (-3450 3950) BN 6
J 0
(-3462 3958);
DISPLAY 0.489362 (-3462 3958);
PAINT GREEN (-3462 3958);
FORCEPROP 2 LAST CDS_LIB mstr_standard
J 0
(-3400 3950);
DISPLAY 0.723404 (-3400 3950);
PAINT MONO (-3400 3950);
DISPLAY INVISIBLE (-3400 3950);
FORCEPROP 1 LAST BODY_TYPE PLUMBING
J 0
(-3400 4000);
DISPLAY 0.872340 (-3400 4000);
PAINT GREEN (-3400 4000);
DISPLAY INVISIBLE (-3400 4000);
FORCEPROP 1 LAST HDL_TAP TRUE
J 0
(-3075 3825);
DISPLAY 0.872340 (-3075 3825);
DISPLAY INVISIBLE (-3075 3825);
FORCEPROP 1 LAST PATH I201
J 0
(-3402 3950);
DISPLAY 0.872340 (-3402 3950);
PAINT GREEN (-3402 3950);
DISPLAY INVISIBLE (-3402 3950);
FORCEADD TAP..1
(-3400 3900);
FORCEPROP 3 LASTPIN (-3450 3900) SIG_NAME M_E_CPU0_SB_DQ<7>
J 0
(-3440 3910);
DISPLAY 0.659574 (-3440 3910);
PAINT MONO (-3440 3910);
DISPLAY INVISIBLE (-3440 3910);
FORCEPROP 1 LASTPIN (-3450 3900) BN 7
J 0
(-3462 3908);
DISPLAY 0.489362 (-3462 3908);
PAINT GREEN (-3462 3908);
FORCEPROP 2 LAST CDS_LIB mstr_standard
J 0
(-3400 3900);
DISPLAY 0.723404 (-3400 3900);
PAINT MONO (-3400 3900);
DISPLAY INVISIBLE (-3400 3900);
FORCEPROP 1 LAST BODY_TYPE PLUMBING
J 0
(-3400 3950);
DISPLAY 0.872340 (-3400 3950);
PAINT GREEN (-3400 3950);
DISPLAY INVISIBLE (-3400 3950);
FORCEPROP 1 LAST HDL_TAP TRUE
J 0
(-3075 3775);
DISPLAY 0.872340 (-3075 3775);
DISPLAY INVISIBLE (-3075 3775);
FORCEPROP 1 LAST PATH I202
J 0
(-3402 3900);
DISPLAY 0.872340 (-3402 3900);
PAINT GREEN (-3402 3900);
DISPLAY INVISIBLE (-3402 3900);
FORCEADD TAP..1
(-3400 3800);
FORCEPROP 3 LASTPIN (-3450 3800) SIG_NAME M_E_CPU0_SB_DQ<8>
J 0
(-3440 3810);
DISPLAY 0.659574 (-3440 3810);
PAINT MONO (-3440 3810);
DISPLAY INVISIBLE (-3440 3810);
FORCEPROP 1 LASTPIN (-3450 3800) BN 8
J 0
(-3462 3808);
DISPLAY 0.489362 (-3462 3808);
PAINT GREEN (-3462 3808);
FORCEPROP 2 LAST CDS_LIB mstr_standard
J 0
(-3400 3800);
DISPLAY 0.723404 (-3400 3800);
PAINT MONO (-3400 3800);
DISPLAY INVISIBLE (-3400 3800);
FORCEPROP 1 LAST BODY_TYPE PLUMBING
J 0
(-3400 3850);
DISPLAY 0.872340 (-3400 3850);
PAINT GREEN (-3400 3850);
DISPLAY INVISIBLE (-3400 3850);
FORCEPROP 1 LAST HDL_TAP TRUE
J 0
(-3075 3675);
DISPLAY 0.872340 (-3075 3675);
DISPLAY INVISIBLE (-3075 3675);
FORCEPROP 1 LAST PATH I203
J 0
(-3402 3800);
DISPLAY 0.872340 (-3402 3800);
PAINT GREEN (-3402 3800);
DISPLAY INVISIBLE (-3402 3800);
FORCEADD TAP..1
(-3400 3750);
FORCEPROP 3 LASTPIN (-3450 3750) SIG_NAME M_E_CPU0_SB_DQ<9>
J 0
(-3440 3760);
DISPLAY 0.659574 (-3440 3760);
PAINT MONO (-3440 3760);
DISPLAY INVISIBLE (-3440 3760);
FORCEPROP 1 LASTPIN (-3450 3750) BN 9
J 0
(-3462 3758);
DISPLAY 0.489362 (-3462 3758);
PAINT GREEN (-3462 3758);
FORCEPROP 2 LAST CDS_LIB mstr_standard
J 0
(-3400 3750);
DISPLAY 0.723404 (-3400 3750);
PAINT MONO (-3400 3750);
DISPLAY INVISIBLE (-3400 3750);
FORCEPROP 1 LAST BODY_TYPE PLUMBING
J 0
(-3400 3800);
DISPLAY 0.872340 (-3400 3800);
PAINT GREEN (-3400 3800);
DISPLAY INVISIBLE (-3400 3800);
FORCEPROP 1 LAST HDL_TAP TRUE
J 0
(-3075 3625);
DISPLAY 0.872340 (-3075 3625);
DISPLAY INVISIBLE (-3075 3625);
FORCEPROP 1 LAST PATH I204
J 0
(-3402 3750);
DISPLAY 0.872340 (-3402 3750);
PAINT GREEN (-3402 3750);
DISPLAY INVISIBLE (-3402 3750);
FORCEADD TAP..1
(-3400 3600);
FORCEPROP 3 LASTPIN (-3450 3600) SIG_NAME M_E_CPU0_SB_DQ<12>
J 0
(-3440 3610);
DISPLAY 0.659574 (-3440 3610);
PAINT MONO (-3440 3610);
DISPLAY INVISIBLE (-3440 3610);
FORCEPROP 1 LASTPIN (-3450 3600) BN 12
J 0
(-3462 3608);
DISPLAY 0.489362 (-3462 3608);
PAINT GREEN (-3462 3608);
FORCEPROP 2 LAST CDS_LIB mstr_standard
J 0
(-3400 3600);
DISPLAY 0.723404 (-3400 3600);
PAINT MONO (-3400 3600);
DISPLAY INVISIBLE (-3400 3600);
FORCEPROP 1 LAST BODY_TYPE PLUMBING
J 0
(-3400 3650);
DISPLAY 0.872340 (-3400 3650);
PAINT GREEN (-3400 3650);
DISPLAY INVISIBLE (-3400 3650);
FORCEPROP 1 LAST HDL_TAP TRUE
J 0
(-3075 3475);
DISPLAY 0.872340 (-3075 3475);
DISPLAY INVISIBLE (-3075 3475);
FORCEPROP 1 LAST PATH I205
J 0
(-3402 3600);
DISPLAY 0.872340 (-3402 3600);
PAINT GREEN (-3402 3600);
DISPLAY INVISIBLE (-3402 3600);
FORCEADD TAP..1
(-3400 3650);
FORCEPROP 3 LASTPIN (-3450 3650) SIG_NAME M_E_CPU0_SB_DQ<11>
J 0
(-3440 3660);
DISPLAY 0.659574 (-3440 3660);
PAINT MONO (-3440 3660);
DISPLAY INVISIBLE (-3440 3660);
FORCEPROP 1 LASTPIN (-3450 3650) BN 11
J 0
(-3462 3658);
DISPLAY 0.489362 (-3462 3658);
PAINT GREEN (-3462 3658);
FORCEPROP 2 LAST CDS_LIB mstr_standard
J 0
(-3400 3650);
DISPLAY 0.723404 (-3400 3650);
PAINT MONO (-3400 3650);
DISPLAY INVISIBLE (-3400 3650);
FORCEPROP 1 LAST BODY_TYPE PLUMBING
J 0
(-3400 3700);
DISPLAY 0.872340 (-3400 3700);
PAINT GREEN (-3400 3700);
DISPLAY INVISIBLE (-3400 3700);
FORCEPROP 1 LAST HDL_TAP TRUE
J 0
(-3075 3525);
DISPLAY 0.872340 (-3075 3525);
DISPLAY INVISIBLE (-3075 3525);
FORCEPROP 1 LAST PATH I206
J 0
(-3402 3650);
DISPLAY 0.872340 (-3402 3650);
PAINT GREEN (-3402 3650);
DISPLAY INVISIBLE (-3402 3650);
FORCEADD TAP..1
(-3400 3700);
FORCEPROP 3 LASTPIN (-3450 3700) SIG_NAME M_E_CPU0_SB_DQ<10>
J 0
(-3440 3710);
DISPLAY 0.659574 (-3440 3710);
PAINT MONO (-3440 3710);
DISPLAY INVISIBLE (-3440 3710);
FORCEPROP 1 LASTPIN (-3450 3700) BN 10
J 0
(-3462 3708);
DISPLAY 0.489362 (-3462 3708);
PAINT GREEN (-3462 3708);
FORCEPROP 2 LAST CDS_LIB mstr_standard
J 0
(-3400 3700);
DISPLAY 0.723404 (-3400 3700);
PAINT MONO (-3400 3700);
DISPLAY INVISIBLE (-3400 3700);
FORCEPROP 1 LAST BODY_TYPE PLUMBING
J 0
(-3400 3750);
DISPLAY 0.872340 (-3400 3750);
PAINT GREEN (-3400 3750);
DISPLAY INVISIBLE (-3400 3750);
FORCEPROP 1 LAST HDL_TAP TRUE
J 0
(-3075 3575);
DISPLAY 0.872340 (-3075 3575);
DISPLAY INVISIBLE (-3075 3575);
FORCEPROP 1 LAST PATH I207
J 0
(-3402 3700);
DISPLAY 0.872340 (-3402 3700);
PAINT GREEN (-3402 3700);
DISPLAY INVISIBLE (-3402 3700);
FORCEADD TAP..1
(-3400 3500);
FORCEPROP 3 LASTPIN (-3450 3500) SIG_NAME M_E_CPU0_SB_DQ<14>
J 0
(-3440 3510);
DISPLAY 0.659574 (-3440 3510);
PAINT MONO (-3440 3510);
DISPLAY INVISIBLE (-3440 3510);
FORCEPROP 1 LASTPIN (-3450 3500) BN 14
J 0
(-3462 3508);
DISPLAY 0.489362 (-3462 3508);
PAINT GREEN (-3462 3508);
FORCEPROP 2 LAST CDS_LIB mstr_standard
J 0
(-3400 3500);
DISPLAY 0.723404 (-3400 3500);
PAINT MONO (-3400 3500);
DISPLAY INVISIBLE (-3400 3500);
FORCEPROP 1 LAST BODY_TYPE PLUMBING
J 0
(-3400 3550);
DISPLAY 0.872340 (-3400 3550);
PAINT GREEN (-3400 3550);
DISPLAY INVISIBLE (-3400 3550);
FORCEPROP 1 LAST HDL_TAP TRUE
J 0
(-3075 3375);
DISPLAY 0.872340 (-3075 3375);
DISPLAY INVISIBLE (-3075 3375);
FORCEPROP 1 LAST PATH I208
J 0
(-3402 3500);
DISPLAY 0.872340 (-3402 3500);
PAINT GREEN (-3402 3500);
DISPLAY INVISIBLE (-3402 3500);
FORCEADD TAP..1
(-3400 3550);
FORCEPROP 3 LASTPIN (-3450 3550) SIG_NAME M_E_CPU0_SB_DQ<13>
J 0
(-3440 3560);
DISPLAY 0.659574 (-3440 3560);
PAINT MONO (-3440 3560);
DISPLAY INVISIBLE (-3440 3560);
FORCEPROP 1 LASTPIN (-3450 3550) BN 13
J 0
(-3462 3558);
DISPLAY 0.489362 (-3462 3558);
PAINT GREEN (-3462 3558);
FORCEPROP 2 LAST CDS_LIB mstr_standard
J 0
(-3400 3550);
DISPLAY 0.723404 (-3400 3550);
PAINT MONO (-3400 3550);
DISPLAY INVISIBLE (-3400 3550);
FORCEPROP 1 LAST BODY_TYPE PLUMBING
J 0
(-3400 3600);
DISPLAY 0.872340 (-3400 3600);
PAINT GREEN (-3400 3600);
DISPLAY INVISIBLE (-3400 3600);
FORCEPROP 1 LAST HDL_TAP TRUE
J 0
(-3075 3425);
DISPLAY 0.872340 (-3075 3425);
DISPLAY INVISIBLE (-3075 3425);
FORCEPROP 1 LAST PATH I209
J 0
(-3402 3550);
DISPLAY 0.872340 (-3402 3550);
PAINT GREEN (-3402 3550);
DISPLAY INVISIBLE (-3402 3550);
FORCEADD TAP..1
(-3400 3450);
FORCEPROP 3 LASTPIN (-3450 3450) SIG_NAME M_E_CPU0_SB_DQ<15>
J 0
(-3440 3460);
DISPLAY 0.659574 (-3440 3460);
PAINT MONO (-3440 3460);
DISPLAY INVISIBLE (-3440 3460);
FORCEPROP 1 LASTPIN (-3450 3450) BN 15
J 0
(-3462 3458);
DISPLAY 0.489362 (-3462 3458);
PAINT GREEN (-3462 3458);
FORCEPROP 2 LAST CDS_LIB mstr_standard
J 0
(-3400 3450);
DISPLAY 0.723404 (-3400 3450);
PAINT MONO (-3400 3450);
DISPLAY INVISIBLE (-3400 3450);
FORCEPROP 1 LAST BODY_TYPE PLUMBING
J 0
(-3400 3500);
DISPLAY 0.872340 (-3400 3500);
PAINT GREEN (-3400 3500);
DISPLAY INVISIBLE (-3400 3500);
FORCEPROP 1 LAST HDL_TAP TRUE
J 0
(-3075 3325);
DISPLAY 0.872340 (-3075 3325);
DISPLAY INVISIBLE (-3075 3325);
FORCEPROP 1 LAST PATH I210
J 0
(-3402 3450);
DISPLAY 0.872340 (-3402 3450);
PAINT GREEN (-3402 3450);
DISPLAY INVISIBLE (-3402 3450);
FORCEADD TAP..1
(-3400 3350);
FORCEPROP 3 LASTPIN (-3450 3350) SIG_NAME M_E_CPU0_SB_DQ<16>
J 0
(-3440 3360);
DISPLAY 0.659574 (-3440 3360);
PAINT MONO (-3440 3360);
DISPLAY INVISIBLE (-3440 3360);
FORCEPROP 1 LASTPIN (-3450 3350) BN 16
J 0
(-3462 3358);
DISPLAY 0.489362 (-3462 3358);
PAINT GREEN (-3462 3358);
FORCEPROP 2 LAST CDS_LIB mstr_standard
J 0
(-3400 3350);
DISPLAY 0.723404 (-3400 3350);
PAINT MONO (-3400 3350);
DISPLAY INVISIBLE (-3400 3350);
FORCEPROP 1 LAST BODY_TYPE PLUMBING
J 0
(-3400 3400);
DISPLAY 0.872340 (-3400 3400);
PAINT GREEN (-3400 3400);
DISPLAY INVISIBLE (-3400 3400);
FORCEPROP 1 LAST HDL_TAP TRUE
J 0
(-3075 3225);
DISPLAY 0.872340 (-3075 3225);
DISPLAY INVISIBLE (-3075 3225);
FORCEPROP 1 LAST PATH I211
J 0
(-3402 3350);
DISPLAY 0.872340 (-3402 3350);
PAINT GREEN (-3402 3350);
DISPLAY INVISIBLE (-3402 3350);
FORCEADD TAP..1
(-3400 3300);
FORCEPROP 3 LASTPIN (-3450 3300) SIG_NAME M_E_CPU0_SB_DQ<17>
J 0
(-3440 3310);
DISPLAY 0.659574 (-3440 3310);
PAINT MONO (-3440 3310);
DISPLAY INVISIBLE (-3440 3310);
FORCEPROP 1 LASTPIN (-3450 3300) BN 17
J 0
(-3462 3308);
DISPLAY 0.489362 (-3462 3308);
PAINT GREEN (-3462 3308);
FORCEPROP 2 LAST CDS_LIB mstr_standard
J 0
(-3400 3300);
DISPLAY 0.723404 (-3400 3300);
PAINT MONO (-3400 3300);
DISPLAY INVISIBLE (-3400 3300);
FORCEPROP 1 LAST BODY_TYPE PLUMBING
J 0
(-3400 3350);
DISPLAY 0.872340 (-3400 3350);
PAINT GREEN (-3400 3350);
DISPLAY INVISIBLE (-3400 3350);
FORCEPROP 1 LAST HDL_TAP TRUE
J 0
(-3075 3175);
DISPLAY 0.872340 (-3075 3175);
DISPLAY INVISIBLE (-3075 3175);
FORCEPROP 1 LAST PATH I212
J 0
(-3402 3300);
DISPLAY 0.872340 (-3402 3300);
PAINT GREEN (-3402 3300);
DISPLAY INVISIBLE (-3402 3300);
FORCEADD TAP..1
(-3400 3250);
FORCEPROP 3 LASTPIN (-3450 3250) SIG_NAME M_E_CPU0_SB_DQ<18>
J 0
(-3440 3260);
DISPLAY 0.659574 (-3440 3260);
PAINT MONO (-3440 3260);
DISPLAY INVISIBLE (-3440 3260);
FORCEPROP 1 LASTPIN (-3450 3250) BN 18
J 0
(-3462 3258);
DISPLAY 0.489362 (-3462 3258);
PAINT GREEN (-3462 3258);
FORCEPROP 2 LAST CDS_LIB mstr_standard
J 0
(-3400 3250);
DISPLAY 0.723404 (-3400 3250);
PAINT MONO (-3400 3250);
DISPLAY INVISIBLE (-3400 3250);
FORCEPROP 1 LAST BODY_TYPE PLUMBING
J 0
(-3400 3300);
DISPLAY 0.872340 (-3400 3300);
PAINT GREEN (-3400 3300);
DISPLAY INVISIBLE (-3400 3300);
FORCEPROP 1 LAST HDL_TAP TRUE
J 0
(-3075 3125);
DISPLAY 0.872340 (-3075 3125);
DISPLAY INVISIBLE (-3075 3125);
FORCEPROP 1 LAST PATH I213
J 0
(-3402 3250);
DISPLAY 0.872340 (-3402 3250);
PAINT GREEN (-3402 3250);
DISPLAY INVISIBLE (-3402 3250);
FORCEADD TAP..1
(-3400 3200);
FORCEPROP 3 LASTPIN (-3450 3200) SIG_NAME M_E_CPU0_SB_DQ<19>
J 0
(-3440 3210);
DISPLAY 0.659574 (-3440 3210);
PAINT MONO (-3440 3210);
DISPLAY INVISIBLE (-3440 3210);
FORCEPROP 1 LASTPIN (-3450 3200) BN 19
J 0
(-3462 3208);
DISPLAY 0.489362 (-3462 3208);
PAINT GREEN (-3462 3208);
FORCEPROP 2 LAST CDS_LIB mstr_standard
J 0
(-3400 3200);
DISPLAY 0.723404 (-3400 3200);
PAINT MONO (-3400 3200);
DISPLAY INVISIBLE (-3400 3200);
FORCEPROP 1 LAST BODY_TYPE PLUMBING
J 0
(-3400 3250);
DISPLAY 0.872340 (-3400 3250);
PAINT GREEN (-3400 3250);
DISPLAY INVISIBLE (-3400 3250);
FORCEPROP 1 LAST HDL_TAP TRUE
J 0
(-3075 3075);
DISPLAY 0.872340 (-3075 3075);
DISPLAY INVISIBLE (-3075 3075);
FORCEPROP 1 LAST PATH I214
J 0
(-3402 3200);
DISPLAY 0.872340 (-3402 3200);
PAINT GREEN (-3402 3200);
DISPLAY INVISIBLE (-3402 3200);
FORCEADD TAP..1
(-3400 3150);
FORCEPROP 3 LASTPIN (-3450 3150) SIG_NAME M_E_CPU0_SB_DQ<20>
J 0
(-3440 3160);
DISPLAY 0.659574 (-3440 3160);
PAINT MONO (-3440 3160);
DISPLAY INVISIBLE (-3440 3160);
FORCEPROP 1 LASTPIN (-3450 3150) BN 20
J 0
(-3462 3158);
DISPLAY 0.489362 (-3462 3158);
PAINT GREEN (-3462 3158);
FORCEPROP 2 LAST CDS_LIB mstr_standard
J 0
(-3400 3150);
DISPLAY 0.723404 (-3400 3150);
PAINT MONO (-3400 3150);
DISPLAY INVISIBLE (-3400 3150);
FORCEPROP 1 LAST BODY_TYPE PLUMBING
J 0
(-3400 3200);
DISPLAY 0.872340 (-3400 3200);
PAINT GREEN (-3400 3200);
DISPLAY INVISIBLE (-3400 3200);
FORCEPROP 1 LAST HDL_TAP TRUE
J 0
(-3075 3025);
DISPLAY 0.872340 (-3075 3025);
DISPLAY INVISIBLE (-3075 3025);
FORCEPROP 1 LAST PATH I215
J 0
(-3402 3150);
DISPLAY 0.872340 (-3402 3150);
PAINT GREEN (-3402 3150);
DISPLAY INVISIBLE (-3402 3150);
FORCEADD TAP..1
(-3400 3100);
FORCEPROP 3 LASTPIN (-3450 3100) SIG_NAME M_E_CPU0_SB_DQ<21>
J 0
(-3440 3110);
DISPLAY 0.659574 (-3440 3110);
PAINT MONO (-3440 3110);
DISPLAY INVISIBLE (-3440 3110);
FORCEPROP 1 LASTPIN (-3450 3100) BN 21
J 0
(-3462 3108);
DISPLAY 0.489362 (-3462 3108);
PAINT GREEN (-3462 3108);
FORCEPROP 2 LAST CDS_LIB mstr_standard
J 0
(-3400 3100);
DISPLAY 0.723404 (-3400 3100);
PAINT MONO (-3400 3100);
DISPLAY INVISIBLE (-3400 3100);
FORCEPROP 1 LAST BODY_TYPE PLUMBING
J 0
(-3400 3150);
DISPLAY 0.872340 (-3400 3150);
PAINT GREEN (-3400 3150);
DISPLAY INVISIBLE (-3400 3150);
FORCEPROP 1 LAST HDL_TAP TRUE
J 0
(-3075 2975);
DISPLAY 0.872340 (-3075 2975);
DISPLAY INVISIBLE (-3075 2975);
FORCEPROP 1 LAST PATH I216
J 0
(-3402 3100);
DISPLAY 0.872340 (-3402 3100);
PAINT GREEN (-3402 3100);
DISPLAY INVISIBLE (-3402 3100);
FORCEADD TAP..1
(-3400 3000);
FORCEPROP 3 LASTPIN (-3450 3000) SIG_NAME M_E_CPU0_SB_DQ<23>
J 0
(-3440 3010);
DISPLAY 0.659574 (-3440 3010);
PAINT MONO (-3440 3010);
DISPLAY INVISIBLE (-3440 3010);
FORCEPROP 1 LASTPIN (-3450 3000) BN 23
J 0
(-3462 3008);
DISPLAY 0.489362 (-3462 3008);
PAINT GREEN (-3462 3008);
FORCEPROP 2 LAST CDS_LIB mstr_standard
J 0
(-3400 3000);
DISPLAY 0.723404 (-3400 3000);
PAINT MONO (-3400 3000);
DISPLAY INVISIBLE (-3400 3000);
FORCEPROP 1 LAST BODY_TYPE PLUMBING
J 0
(-3400 3050);
DISPLAY 0.872340 (-3400 3050);
PAINT GREEN (-3400 3050);
DISPLAY INVISIBLE (-3400 3050);
FORCEPROP 1 LAST HDL_TAP TRUE
J 0
(-3075 2875);
DISPLAY 0.872340 (-3075 2875);
DISPLAY INVISIBLE (-3075 2875);
FORCEPROP 1 LAST PATH I217
J 0
(-3402 3000);
DISPLAY 0.872340 (-3402 3000);
PAINT GREEN (-3402 3000);
DISPLAY INVISIBLE (-3402 3000);
FORCEADD TAP..1
(-3400 3050);
FORCEPROP 3 LASTPIN (-3450 3050) SIG_NAME M_E_CPU0_SB_DQ<22>
J 0
(-3440 3060);
DISPLAY 0.659574 (-3440 3060);
PAINT MONO (-3440 3060);
DISPLAY INVISIBLE (-3440 3060);
FORCEPROP 1 LASTPIN (-3450 3050) BN 22
J 0
(-3462 3058);
DISPLAY 0.489362 (-3462 3058);
PAINT GREEN (-3462 3058);
FORCEPROP 2 LAST CDS_LIB mstr_standard
J 0
(-3400 3050);
DISPLAY 0.723404 (-3400 3050);
PAINT MONO (-3400 3050);
DISPLAY INVISIBLE (-3400 3050);
FORCEPROP 1 LAST BODY_TYPE PLUMBING
J 0
(-3400 3100);
DISPLAY 0.872340 (-3400 3100);
PAINT GREEN (-3400 3100);
DISPLAY INVISIBLE (-3400 3100);
FORCEPROP 1 LAST HDL_TAP TRUE
J 0
(-3075 2925);
DISPLAY 0.872340 (-3075 2925);
DISPLAY INVISIBLE (-3075 2925);
FORCEPROP 1 LAST PATH I218
J 0
(-3402 3050);
DISPLAY 0.872340 (-3402 3050);
PAINT GREEN (-3402 3050);
DISPLAY INVISIBLE (-3402 3050);
FORCEADD TAP..1
(-3400 2900);
FORCEPROP 3 LASTPIN (-3450 2900) SIG_NAME M_E_CPU0_SB_DQ<24>
J 0
(-3440 2910);
DISPLAY 0.659574 (-3440 2910);
PAINT MONO (-3440 2910);
DISPLAY INVISIBLE (-3440 2910);
FORCEPROP 1 LASTPIN (-3450 2900) BN 24
J 0
(-3462 2908);
DISPLAY 0.489362 (-3462 2908);
PAINT GREEN (-3462 2908);
FORCEPROP 2 LAST CDS_LIB mstr_standard
J 0
(-3400 2900);
DISPLAY 0.723404 (-3400 2900);
PAINT MONO (-3400 2900);
DISPLAY INVISIBLE (-3400 2900);
FORCEPROP 1 LAST BODY_TYPE PLUMBING
J 0
(-3400 2950);
DISPLAY 0.872340 (-3400 2950);
PAINT GREEN (-3400 2950);
DISPLAY INVISIBLE (-3400 2950);
FORCEPROP 1 LAST HDL_TAP TRUE
J 0
(-3075 2775);
DISPLAY 0.872340 (-3075 2775);
DISPLAY INVISIBLE (-3075 2775);
FORCEPROP 1 LAST PATH I219
J 0
(-3402 2900);
DISPLAY 0.872340 (-3402 2900);
PAINT GREEN (-3402 2900);
DISPLAY INVISIBLE (-3402 2900);
FORCEADD TAP..1
(-3400 2850);
FORCEPROP 3 LASTPIN (-3450 2850) SIG_NAME M_E_CPU0_SB_DQ<25>
J 0
(-3440 2860);
DISPLAY 0.659574 (-3440 2860);
PAINT MONO (-3440 2860);
DISPLAY INVISIBLE (-3440 2860);
FORCEPROP 1 LASTPIN (-3450 2850) BN 25
J 0
(-3462 2858);
DISPLAY 0.489362 (-3462 2858);
PAINT GREEN (-3462 2858);
FORCEPROP 2 LAST CDS_LIB mstr_standard
J 0
(-3400 2850);
DISPLAY 0.723404 (-3400 2850);
PAINT MONO (-3400 2850);
DISPLAY INVISIBLE (-3400 2850);
FORCEPROP 1 LAST BODY_TYPE PLUMBING
J 0
(-3400 2900);
DISPLAY 0.872340 (-3400 2900);
PAINT GREEN (-3400 2900);
DISPLAY INVISIBLE (-3400 2900);
FORCEPROP 1 LAST HDL_TAP TRUE
J 0
(-3075 2725);
DISPLAY 0.872340 (-3075 2725);
DISPLAY INVISIBLE (-3075 2725);
FORCEPROP 1 LAST PATH I220
J 0
(-3402 2850);
DISPLAY 0.872340 (-3402 2850);
PAINT GREEN (-3402 2850);
DISPLAY INVISIBLE (-3402 2850);
FORCEADD TAP..1
(-3400 2800);
FORCEPROP 3 LASTPIN (-3450 2800) SIG_NAME M_E_CPU0_SB_DQ<26>
J 0
(-3440 2810);
DISPLAY 0.659574 (-3440 2810);
PAINT MONO (-3440 2810);
DISPLAY INVISIBLE (-3440 2810);
FORCEPROP 1 LASTPIN (-3450 2800) BN 26
J 0
(-3462 2808);
DISPLAY 0.489362 (-3462 2808);
PAINT GREEN (-3462 2808);
FORCEPROP 2 LAST CDS_LIB mstr_standard
J 0
(-3400 2800);
DISPLAY 0.723404 (-3400 2800);
PAINT MONO (-3400 2800);
DISPLAY INVISIBLE (-3400 2800);
FORCEPROP 1 LAST BODY_TYPE PLUMBING
J 0
(-3400 2850);
DISPLAY 0.872340 (-3400 2850);
PAINT GREEN (-3400 2850);
DISPLAY INVISIBLE (-3400 2850);
FORCEPROP 1 LAST HDL_TAP TRUE
J 0
(-3075 2675);
DISPLAY 0.872340 (-3075 2675);
DISPLAY INVISIBLE (-3075 2675);
FORCEPROP 1 LAST PATH I221
J 0
(-3402 2800);
DISPLAY 0.872340 (-3402 2800);
PAINT GREEN (-3402 2800);
DISPLAY INVISIBLE (-3402 2800);
FORCEADD TAP..1
(-3400 2750);
FORCEPROP 3 LASTPIN (-3450 2750) SIG_NAME M_E_CPU0_SB_DQ<27>
J 0
(-3440 2760);
DISPLAY 0.659574 (-3440 2760);
PAINT MONO (-3440 2760);
DISPLAY INVISIBLE (-3440 2760);
FORCEPROP 1 LASTPIN (-3450 2750) BN 27
J 0
(-3462 2758);
DISPLAY 0.489362 (-3462 2758);
PAINT GREEN (-3462 2758);
FORCEPROP 2 LAST CDS_LIB mstr_standard
J 0
(-3400 2750);
DISPLAY 0.723404 (-3400 2750);
PAINT MONO (-3400 2750);
DISPLAY INVISIBLE (-3400 2750);
FORCEPROP 1 LAST BODY_TYPE PLUMBING
J 0
(-3400 2800);
DISPLAY 0.872340 (-3400 2800);
PAINT GREEN (-3400 2800);
DISPLAY INVISIBLE (-3400 2800);
FORCEPROP 1 LAST HDL_TAP TRUE
J 0
(-3075 2625);
DISPLAY 0.872340 (-3075 2625);
DISPLAY INVISIBLE (-3075 2625);
FORCEPROP 1 LAST PATH I222
J 0
(-3402 2750);
DISPLAY 0.872340 (-3402 2750);
PAINT GREEN (-3402 2750);
DISPLAY INVISIBLE (-3402 2750);
FORCEADD TAP..1
(-3400 2700);
FORCEPROP 3 LASTPIN (-3450 2700) SIG_NAME M_E_CPU0_SB_DQ<28>
J 0
(-3440 2710);
DISPLAY 0.659574 (-3440 2710);
PAINT MONO (-3440 2710);
DISPLAY INVISIBLE (-3440 2710);
FORCEPROP 1 LASTPIN (-3450 2700) BN 28
J 0
(-3462 2708);
DISPLAY 0.489362 (-3462 2708);
PAINT GREEN (-3462 2708);
FORCEPROP 2 LAST CDS_LIB mstr_standard
J 0
(-3400 2700);
DISPLAY 0.723404 (-3400 2700);
PAINT MONO (-3400 2700);
DISPLAY INVISIBLE (-3400 2700);
FORCEPROP 1 LAST BODY_TYPE PLUMBING
J 0
(-3400 2750);
DISPLAY 0.872340 (-3400 2750);
PAINT GREEN (-3400 2750);
DISPLAY INVISIBLE (-3400 2750);
FORCEPROP 1 LAST HDL_TAP TRUE
J 0
(-3075 2575);
DISPLAY 0.872340 (-3075 2575);
DISPLAY INVISIBLE (-3075 2575);
FORCEPROP 1 LAST PATH I223
J 0
(-3402 2700);
DISPLAY 0.872340 (-3402 2700);
PAINT GREEN (-3402 2700);
DISPLAY INVISIBLE (-3402 2700);
FORCEADD TAP..1
(-3400 2650);
FORCEPROP 3 LASTPIN (-3450 2650) SIG_NAME M_E_CPU0_SB_DQ<29>
J 0
(-3440 2660);
DISPLAY 0.659574 (-3440 2660);
PAINT MONO (-3440 2660);
DISPLAY INVISIBLE (-3440 2660);
FORCEPROP 1 LASTPIN (-3450 2650) BN 29
J 0
(-3462 2658);
DISPLAY 0.489362 (-3462 2658);
PAINT GREEN (-3462 2658);
FORCEPROP 2 LAST CDS_LIB mstr_standard
J 0
(-3400 2650);
DISPLAY 0.723404 (-3400 2650);
PAINT MONO (-3400 2650);
DISPLAY INVISIBLE (-3400 2650);
FORCEPROP 1 LAST BODY_TYPE PLUMBING
J 0
(-3400 2700);
DISPLAY 0.872340 (-3400 2700);
PAINT GREEN (-3400 2700);
DISPLAY INVISIBLE (-3400 2700);
FORCEPROP 1 LAST HDL_TAP TRUE
J 0
(-3075 2525);
DISPLAY 0.872340 (-3075 2525);
DISPLAY INVISIBLE (-3075 2525);
FORCEPROP 1 LAST PATH I224
J 0
(-3402 2650);
DISPLAY 0.872340 (-3402 2650);
PAINT GREEN (-3402 2650);
DISPLAY INVISIBLE (-3402 2650);
FORCEADD TAP..1
(-3400 2600);
FORCEPROP 3 LASTPIN (-3450 2600) SIG_NAME M_E_CPU0_SB_DQ<30>
J 0
(-3440 2610);
DISPLAY 0.659574 (-3440 2610);
PAINT MONO (-3440 2610);
DISPLAY INVISIBLE (-3440 2610);
FORCEPROP 1 LASTPIN (-3450 2600) BN 30
J 0
(-3462 2608);
DISPLAY 0.489362 (-3462 2608);
PAINT GREEN (-3462 2608);
FORCEPROP 2 LAST CDS_LIB mstr_standard
J 0
(-3400 2600);
DISPLAY 0.723404 (-3400 2600);
PAINT MONO (-3400 2600);
DISPLAY INVISIBLE (-3400 2600);
FORCEPROP 1 LAST BODY_TYPE PLUMBING
J 0
(-3400 2650);
DISPLAY 0.872340 (-3400 2650);
PAINT GREEN (-3400 2650);
DISPLAY INVISIBLE (-3400 2650);
FORCEPROP 1 LAST HDL_TAP TRUE
J 0
(-3075 2475);
DISPLAY 0.872340 (-3075 2475);
DISPLAY INVISIBLE (-3075 2475);
FORCEPROP 1 LAST PATH I225
J 0
(-3402 2600);
DISPLAY 0.872340 (-3402 2600);
PAINT GREEN (-3402 2600);
DISPLAY INVISIBLE (-3402 2600);
FORCEADD TAP..1
(-3400 2450);
FORCEPROP 3 LASTPIN (-3450 2450) SIG_NAME M_E_CPU0_SA_CB<0>
J 0
(-3440 2460);
DISPLAY 0.659574 (-3440 2460);
PAINT MONO (-3440 2460);
DISPLAY INVISIBLE (-3440 2460);
FORCEPROP 1 LASTPIN (-3450 2450) BN 0
J 0
(-3462 2458);
DISPLAY 0.489362 (-3462 2458);
PAINT GREEN (-3462 2458);
FORCEPROP 2 LAST CDS_LIB mstr_standard
J 2
(-3400 2450);
DISPLAY 0.723404 (-3400 2450);
PAINT MONO (-3400 2450);
DISPLAY INVISIBLE (-3400 2450);
FORCEPROP 1 LAST BODY_TYPE PLUMBING
J 0
(-3400 2500);
DISPLAY 0.872340 (-3400 2500);
PAINT GREEN (-3400 2500);
DISPLAY INVISIBLE (-3400 2500);
FORCEPROP 1 LAST HDL_TAP TRUE
J 0
(-3075 2325);
DISPLAY 0.872340 (-3075 2325);
DISPLAY INVISIBLE (-3075 2325);
FORCEPROP 1 LAST PATH I226
J 0
(-3402 2450);
DISPLAY 0.872340 (-3402 2450);
PAINT GREEN (-3402 2450);
DISPLAY INVISIBLE (-3402 2450);
FORCEADD TAP..1
(-3400 2550);
FORCEPROP 3 LASTPIN (-3450 2550) SIG_NAME M_E_CPU0_SB_DQ<31>
J 0
(-3440 2560);
DISPLAY 0.659574 (-3440 2560);
PAINT MONO (-3440 2560);
DISPLAY INVISIBLE (-3440 2560);
FORCEPROP 1 LASTPIN (-3450 2550) BN 31
J 0
(-3462 2558);
DISPLAY 0.489362 (-3462 2558);
PAINT GREEN (-3462 2558);
FORCEPROP 2 LAST CDS_LIB mstr_standard
J 0
(-3400 2550);
DISPLAY 0.723404 (-3400 2550);
PAINT MONO (-3400 2550);
DISPLAY INVISIBLE (-3400 2550);
FORCEPROP 1 LAST BODY_TYPE PLUMBING
J 0
(-3400 2600);
DISPLAY 0.872340 (-3400 2600);
PAINT GREEN (-3400 2600);
DISPLAY INVISIBLE (-3400 2600);
FORCEPROP 1 LAST HDL_TAP TRUE
J 0
(-3075 2425);
DISPLAY 0.872340 (-3075 2425);
DISPLAY INVISIBLE (-3075 2425);
FORCEPROP 1 LAST PATH I227
J 0
(-3402 2550);
DISPLAY 0.872340 (-3402 2550);
PAINT GREEN (-3402 2550);
DISPLAY INVISIBLE (-3402 2550);
FORCEADD TAP..1
(-3400 2350);
FORCEPROP 3 LASTPIN (-3450 2350) SIG_NAME M_E_CPU0_SA_CB<2>
J 0
(-3440 2360);
DISPLAY 0.659574 (-3440 2360);
PAINT MONO (-3440 2360);
DISPLAY INVISIBLE (-3440 2360);
FORCEPROP 1 LASTPIN (-3450 2350) BN 2
J 0
(-3462 2358);
DISPLAY 0.489362 (-3462 2358);
PAINT GREEN (-3462 2358);
FORCEPROP 2 LAST CDS_LIB mstr_standard
J 2
(-3400 2350);
DISPLAY 0.723404 (-3400 2350);
PAINT MONO (-3400 2350);
DISPLAY INVISIBLE (-3400 2350);
FORCEPROP 1 LAST BODY_TYPE PLUMBING
J 0
(-3400 2400);
DISPLAY 0.872340 (-3400 2400);
PAINT GREEN (-3400 2400);
DISPLAY INVISIBLE (-3400 2400);
FORCEPROP 1 LAST HDL_TAP TRUE
J 0
(-3075 2225);
DISPLAY 0.872340 (-3075 2225);
DISPLAY INVISIBLE (-3075 2225);
FORCEPROP 1 LAST PATH I228
J 0
(-3402 2350);
DISPLAY 0.872340 (-3402 2350);
PAINT GREEN (-3402 2350);
DISPLAY INVISIBLE (-3402 2350);
FORCEADD TAP..1
(-3400 2400);
FORCEPROP 3 LASTPIN (-3450 2400) SIG_NAME M_E_CPU0_SA_CB<1>
J 0
(-3440 2410);
DISPLAY 0.659574 (-3440 2410);
PAINT MONO (-3440 2410);
DISPLAY INVISIBLE (-3440 2410);
FORCEPROP 1 LASTPIN (-3450 2400) BN 1
J 0
(-3462 2408);
DISPLAY 0.489362 (-3462 2408);
PAINT GREEN (-3462 2408);
FORCEPROP 2 LAST CDS_LIB mstr_standard
J 2
(-3400 2400);
DISPLAY 0.723404 (-3400 2400);
PAINT MONO (-3400 2400);
DISPLAY INVISIBLE (-3400 2400);
FORCEPROP 1 LAST BODY_TYPE PLUMBING
J 0
(-3400 2450);
DISPLAY 0.872340 (-3400 2450);
PAINT GREEN (-3400 2450);
DISPLAY INVISIBLE (-3400 2450);
FORCEPROP 1 LAST HDL_TAP TRUE
J 0
(-3075 2275);
DISPLAY 0.872340 (-3075 2275);
DISPLAY INVISIBLE (-3075 2275);
FORCEPROP 1 LAST PATH I229
J 0
(-3402 2400);
DISPLAY 0.872340 (-3402 2400);
PAINT GREEN (-3402 2400);
DISPLAY INVISIBLE (-3402 2400);
FORCEADD TAP..1
(-3400 2250);
FORCEPROP 3 LASTPIN (-3450 2250) SIG_NAME M_E_CPU0_SA_CB<4>
J 0
(-3440 2260);
DISPLAY 0.659574 (-3440 2260);
PAINT MONO (-3440 2260);
DISPLAY INVISIBLE (-3440 2260);
FORCEPROP 1 LASTPIN (-3450 2250) BN 4
J 0
(-3462 2258);
DISPLAY 0.489362 (-3462 2258);
PAINT GREEN (-3462 2258);
FORCEPROP 2 LAST CDS_LIB mstr_standard
J 2
(-3400 2250);
DISPLAY 0.723404 (-3400 2250);
PAINT MONO (-3400 2250);
DISPLAY INVISIBLE (-3400 2250);
FORCEPROP 1 LAST BODY_TYPE PLUMBING
J 0
(-3400 2300);
DISPLAY 0.872340 (-3400 2300);
PAINT GREEN (-3400 2300);
DISPLAY INVISIBLE (-3400 2300);
FORCEPROP 1 LAST HDL_TAP TRUE
J 0
(-3075 2125);
DISPLAY 0.872340 (-3075 2125);
DISPLAY INVISIBLE (-3075 2125);
FORCEPROP 1 LAST PATH I230
J 0
(-3402 2250);
DISPLAY 0.872340 (-3402 2250);
PAINT GREEN (-3402 2250);
DISPLAY INVISIBLE (-3402 2250);
FORCEADD TAP..1
(-3400 2300);
FORCEPROP 3 LASTPIN (-3450 2300) SIG_NAME M_E_CPU0_SA_CB<3>
J 0
(-3440 2310);
DISPLAY 0.659574 (-3440 2310);
PAINT MONO (-3440 2310);
DISPLAY INVISIBLE (-3440 2310);
FORCEPROP 1 LASTPIN (-3450 2300) BN 3
J 0
(-3462 2308);
DISPLAY 0.489362 (-3462 2308);
PAINT GREEN (-3462 2308);
FORCEPROP 2 LAST CDS_LIB mstr_standard
J 2
(-3400 2300);
DISPLAY 0.723404 (-3400 2300);
PAINT MONO (-3400 2300);
DISPLAY INVISIBLE (-3400 2300);
FORCEPROP 1 LAST BODY_TYPE PLUMBING
J 0
(-3400 2350);
DISPLAY 0.872340 (-3400 2350);
PAINT GREEN (-3400 2350);
DISPLAY INVISIBLE (-3400 2350);
FORCEPROP 1 LAST HDL_TAP TRUE
J 0
(-3075 2175);
DISPLAY 0.872340 (-3075 2175);
DISPLAY INVISIBLE (-3075 2175);
FORCEPROP 1 LAST PATH I231
J 0
(-3402 2300);
DISPLAY 0.872340 (-3402 2300);
PAINT GREEN (-3402 2300);
DISPLAY INVISIBLE (-3402 2300);
FORCEADD TAP..1
(-3400 2200);
FORCEPROP 3 LASTPIN (-3450 2200) SIG_NAME M_E_CPU0_SA_CB<5>
J 0
(-3440 2210);
DISPLAY 0.659574 (-3440 2210);
PAINT MONO (-3440 2210);
DISPLAY INVISIBLE (-3440 2210);
FORCEPROP 1 LASTPIN (-3450 2200) BN 5
J 0
(-3462 2208);
DISPLAY 0.489362 (-3462 2208);
PAINT GREEN (-3462 2208);
FORCEPROP 2 LAST CDS_LIB mstr_standard
J 2
(-3400 2200);
DISPLAY 0.723404 (-3400 2200);
PAINT MONO (-3400 2200);
DISPLAY INVISIBLE (-3400 2200);
FORCEPROP 1 LAST BODY_TYPE PLUMBING
J 0
(-3400 2250);
DISPLAY 0.872340 (-3400 2250);
PAINT GREEN (-3400 2250);
DISPLAY INVISIBLE (-3400 2250);
FORCEPROP 1 LAST HDL_TAP TRUE
J 0
(-3075 2075);
DISPLAY 0.872340 (-3075 2075);
DISPLAY INVISIBLE (-3075 2075);
FORCEPROP 1 LAST PATH I232
J 0
(-3402 2200);
DISPLAY 0.872340 (-3402 2200);
PAINT GREEN (-3402 2200);
DISPLAY INVISIBLE (-3402 2200);
FORCEADD TAP..1
(-3400 2150);
FORCEPROP 3 LASTPIN (-3450 2150) SIG_NAME M_E_CPU0_SA_CB<6>
J 0
(-3440 2160);
DISPLAY 0.659574 (-3440 2160);
PAINT MONO (-3440 2160);
DISPLAY INVISIBLE (-3440 2160);
FORCEPROP 1 LASTPIN (-3450 2150) BN 6
J 0
(-3462 2158);
DISPLAY 0.489362 (-3462 2158);
PAINT GREEN (-3462 2158);
FORCEPROP 2 LAST CDS_LIB mstr_standard
J 2
(-3400 2150);
DISPLAY 0.723404 (-3400 2150);
PAINT MONO (-3400 2150);
DISPLAY INVISIBLE (-3400 2150);
FORCEPROP 1 LAST BODY_TYPE PLUMBING
J 0
(-3400 2200);
DISPLAY 0.872340 (-3400 2200);
PAINT GREEN (-3400 2200);
DISPLAY INVISIBLE (-3400 2200);
FORCEPROP 1 LAST HDL_TAP TRUE
J 0
(-3075 2025);
DISPLAY 0.872340 (-3075 2025);
DISPLAY INVISIBLE (-3075 2025);
FORCEPROP 1 LAST PATH I233
J 0
(-3402 2150);
DISPLAY 0.872340 (-3402 2150);
PAINT GREEN (-3402 2150);
DISPLAY INVISIBLE (-3402 2150);
FORCEADD TAP..1
(-3400 2100);
FORCEPROP 3 LASTPIN (-3450 2100) SIG_NAME M_E_CPU0_SA_CB<7>
J 0
(-3440 2110);
DISPLAY 0.659574 (-3440 2110);
PAINT MONO (-3440 2110);
DISPLAY INVISIBLE (-3440 2110);
FORCEPROP 1 LASTPIN (-3450 2100) BN 7
J 0
(-3462 2108);
DISPLAY 0.489362 (-3462 2108);
PAINT GREEN (-3462 2108);
FORCEPROP 2 LAST CDS_LIB mstr_standard
J 2
(-3400 2100);
DISPLAY 0.723404 (-3400 2100);
PAINT MONO (-3400 2100);
DISPLAY INVISIBLE (-3400 2100);
FORCEPROP 1 LAST BODY_TYPE PLUMBING
J 0
(-3400 2150);
DISPLAY 0.872340 (-3400 2150);
PAINT GREEN (-3400 2150);
DISPLAY INVISIBLE (-3400 2150);
FORCEPROP 1 LAST HDL_TAP TRUE
J 0
(-3075 1975);
DISPLAY 0.872340 (-3075 1975);
DISPLAY INVISIBLE (-3075 1975);
FORCEPROP 1 LAST PATH I234
J 0
(-3402 2100);
DISPLAY 0.872340 (-3402 2100);
PAINT GREEN (-3402 2100);
DISPLAY INVISIBLE (-3402 2100);
FORCEADD OFFPAGE..6
R 2
(-2800 2050);
FORCEPROP 2 LAST $XR0 89 
J 0
(-2586 2050);
DISPLAY 0.638298 (-2586 2050);
PAINT MONO (-2586 2050);
FORCEPROP 2 LAST PATH I235
J 0
(-2575 2100);
DISPLAY 1.021277 (-2575 2100);
DISPLAY INVISIBLE (-2575 2100);
FORCEPROP 1 LAST COMMENT_BODY TRUE
J 2
(-2900 1975);
DISPLAY 0.872340 (-2900 1975);
PAINT GREEN (-2900 1975);
DISPLAY INVISIBLE (-2900 1975);
FORCEPROP 1 LAST OFFPAGE TRUE
J 2
(-3125 1925);
DISPLAY 0.872340 (-3125 1925);
PAINT GREEN (-3125 1925);
DISPLAY INVISIBLE (-3125 1925);
FORCEPROP 2 LAST CDS_LIB mstr_standard
J 2
(-2800 2050);
DISPLAY 0.723404 (-2800 2050);
PAINT MONO (-2800 2050);
DISPLAY INVISIBLE (-2800 2050);
FORCEADD TAP..1
(-3400 1950);
FORCEPROP 3 LASTPIN (-3450 1950) SIG_NAME M_E_CPU0_SB_CB<1>
J 0
(-3440 1960);
DISPLAY 0.659574 (-3440 1960);
PAINT MONO (-3440 1960);
DISPLAY INVISIBLE (-3440 1960);
FORCEPROP 1 LASTPIN (-3450 1950) BN 1
J 0
(-3462 1958);
DISPLAY 0.489362 (-3462 1958);
PAINT GREEN (-3462 1958);
FORCEPROP 2 LAST CDS_LIB mstr_standard
J 2
(-3400 1950);
DISPLAY 0.723404 (-3400 1950);
PAINT MONO (-3400 1950);
DISPLAY INVISIBLE (-3400 1950);
FORCEPROP 1 LAST BODY_TYPE PLUMBING
J 0
(-3400 2000);
DISPLAY 0.872340 (-3400 2000);
PAINT GREEN (-3400 2000);
DISPLAY INVISIBLE (-3400 2000);
FORCEPROP 1 LAST HDL_TAP TRUE
J 0
(-3075 1825);
DISPLAY 0.872340 (-3075 1825);
DISPLAY INVISIBLE (-3075 1825);
FORCEPROP 1 LAST PATH I236
J 0
(-3402 1950);
DISPLAY 0.872340 (-3402 1950);
PAINT GREEN (-3402 1950);
DISPLAY INVISIBLE (-3402 1950);
FORCEADD TAP..1
(-3400 2000);
FORCEPROP 3 LASTPIN (-3450 2000) SIG_NAME M_E_CPU0_SB_CB<0>
J 0
(-3440 2010);
DISPLAY 0.659574 (-3440 2010);
PAINT MONO (-3440 2010);
DISPLAY INVISIBLE (-3440 2010);
FORCEPROP 1 LASTPIN (-3450 2000) BN 0
J 0
(-3462 2008);
DISPLAY 0.489362 (-3462 2008);
PAINT GREEN (-3462 2008);
FORCEPROP 2 LAST CDS_LIB mstr_standard
J 2
(-3400 2000);
DISPLAY 0.723404 (-3400 2000);
PAINT MONO (-3400 2000);
DISPLAY INVISIBLE (-3400 2000);
FORCEPROP 1 LAST BODY_TYPE PLUMBING
J 0
(-3400 2050);
DISPLAY 0.872340 (-3400 2050);
PAINT GREEN (-3400 2050);
DISPLAY INVISIBLE (-3400 2050);
FORCEPROP 1 LAST HDL_TAP TRUE
J 0
(-3075 1875);
DISPLAY 0.872340 (-3075 1875);
DISPLAY INVISIBLE (-3075 1875);
FORCEPROP 1 LAST PATH I237
J 0
(-3402 2000);
DISPLAY 0.872340 (-3402 2000);
PAINT GREEN (-3402 2000);
DISPLAY INVISIBLE (-3402 2000);
FORCEADD TAP..1
(-3400 1800);
FORCEPROP 3 LASTPIN (-3450 1800) SIG_NAME M_E_CPU0_SB_CB<4>
J 0
(-3440 1810);
DISPLAY 0.659574 (-3440 1810);
PAINT MONO (-3440 1810);
DISPLAY INVISIBLE (-3440 1810);
FORCEPROP 1 LASTPIN (-3450 1800) BN 4
J 0
(-3462 1808);
DISPLAY 0.489362 (-3462 1808);
PAINT GREEN (-3462 1808);
FORCEPROP 2 LAST CDS_LIB mstr_standard
J 2
(-3400 1800);
DISPLAY 0.723404 (-3400 1800);
PAINT MONO (-3400 1800);
DISPLAY INVISIBLE (-3400 1800);
FORCEPROP 1 LAST BODY_TYPE PLUMBING
J 0
(-3400 1850);
DISPLAY 0.872340 (-3400 1850);
PAINT GREEN (-3400 1850);
DISPLAY INVISIBLE (-3400 1850);
FORCEPROP 1 LAST HDL_TAP TRUE
J 0
(-3075 1675);
DISPLAY 0.872340 (-3075 1675);
DISPLAY INVISIBLE (-3075 1675);
FORCEPROP 1 LAST PATH I238
J 0
(-3402 1800);
DISPLAY 0.872340 (-3402 1800);
PAINT GREEN (-3402 1800);
DISPLAY INVISIBLE (-3402 1800);
FORCEADD TAP..1
(-3400 1900);
FORCEPROP 3 LASTPIN (-3450 1900) SIG_NAME M_E_CPU0_SB_CB<2>
J 0
(-3440 1910);
DISPLAY 0.659574 (-3440 1910);
PAINT MONO (-3440 1910);
DISPLAY INVISIBLE (-3440 1910);
FORCEPROP 1 LASTPIN (-3450 1900) BN 2
J 0
(-3462 1908);
DISPLAY 0.489362 (-3462 1908);
PAINT GREEN (-3462 1908);
FORCEPROP 2 LAST CDS_LIB mstr_standard
J 2
(-3400 1900);
DISPLAY 0.723404 (-3400 1900);
PAINT MONO (-3400 1900);
DISPLAY INVISIBLE (-3400 1900);
FORCEPROP 1 LAST BODY_TYPE PLUMBING
J 0
(-3400 1950);
DISPLAY 0.872340 (-3400 1950);
PAINT GREEN (-3400 1950);
DISPLAY INVISIBLE (-3400 1950);
FORCEPROP 1 LAST HDL_TAP TRUE
J 0
(-3075 1775);
DISPLAY 0.872340 (-3075 1775);
DISPLAY INVISIBLE (-3075 1775);
FORCEPROP 1 LAST PATH I239
J 0
(-3402 1900);
DISPLAY 0.872340 (-3402 1900);
PAINT GREEN (-3402 1900);
DISPLAY INVISIBLE (-3402 1900);
FORCEADD TAP..1
(-3400 1850);
FORCEPROP 3 LASTPIN (-3450 1850) SIG_NAME M_E_CPU0_SB_CB<3>
J 0
(-3440 1860);
DISPLAY 0.659574 (-3440 1860);
PAINT MONO (-3440 1860);
DISPLAY INVISIBLE (-3440 1860);
FORCEPROP 1 LASTPIN (-3450 1850) BN 3
J 0
(-3462 1858);
DISPLAY 0.489362 (-3462 1858);
PAINT GREEN (-3462 1858);
FORCEPROP 2 LAST CDS_LIB mstr_standard
J 2
(-3400 1850);
DISPLAY 0.723404 (-3400 1850);
PAINT MONO (-3400 1850);
DISPLAY INVISIBLE (-3400 1850);
FORCEPROP 1 LAST BODY_TYPE PLUMBING
J 0
(-3400 1900);
DISPLAY 0.872340 (-3400 1900);
PAINT GREEN (-3400 1900);
DISPLAY INVISIBLE (-3400 1900);
FORCEPROP 1 LAST HDL_TAP TRUE
J 0
(-3075 1725);
DISPLAY 0.872340 (-3075 1725);
DISPLAY INVISIBLE (-3075 1725);
FORCEPROP 1 LAST PATH I240
J 0
(-3402 1850);
DISPLAY 0.872340 (-3402 1850);
PAINT GREEN (-3402 1850);
DISPLAY INVISIBLE (-3402 1850);
FORCEADD TAP..1
(-3400 1700);
FORCEPROP 3 LASTPIN (-3450 1700) SIG_NAME M_E_CPU0_SB_CB<6>
J 0
(-3440 1710);
DISPLAY 0.659574 (-3440 1710);
PAINT MONO (-3440 1710);
DISPLAY INVISIBLE (-3440 1710);
FORCEPROP 1 LASTPIN (-3450 1700) BN 6
J 0
(-3462 1708);
DISPLAY 0.489362 (-3462 1708);
PAINT GREEN (-3462 1708);
FORCEPROP 2 LAST CDS_LIB mstr_standard
J 2
(-3400 1700);
DISPLAY 0.723404 (-3400 1700);
PAINT MONO (-3400 1700);
DISPLAY INVISIBLE (-3400 1700);
FORCEPROP 1 LAST BODY_TYPE PLUMBING
J 0
(-3400 1750);
DISPLAY 0.872340 (-3400 1750);
PAINT GREEN (-3400 1750);
DISPLAY INVISIBLE (-3400 1750);
FORCEPROP 1 LAST HDL_TAP TRUE
J 0
(-3075 1575);
DISPLAY 0.872340 (-3075 1575);
DISPLAY INVISIBLE (-3075 1575);
FORCEPROP 1 LAST PATH I241
J 0
(-3402 1700);
DISPLAY 0.872340 (-3402 1700);
PAINT GREEN (-3402 1700);
DISPLAY INVISIBLE (-3402 1700);
FORCEADD TAP..1
(-3400 1750);
FORCEPROP 3 LASTPIN (-3450 1750) SIG_NAME M_E_CPU0_SB_CB<5>
J 0
(-3440 1760);
DISPLAY 0.659574 (-3440 1760);
PAINT MONO (-3440 1760);
DISPLAY INVISIBLE (-3440 1760);
FORCEPROP 1 LASTPIN (-3450 1750) BN 5
J 0
(-3462 1758);
DISPLAY 0.489362 (-3462 1758);
PAINT GREEN (-3462 1758);
FORCEPROP 2 LAST CDS_LIB mstr_standard
J 2
(-3400 1750);
DISPLAY 0.723404 (-3400 1750);
PAINT MONO (-3400 1750);
DISPLAY INVISIBLE (-3400 1750);
FORCEPROP 1 LAST BODY_TYPE PLUMBING
J 0
(-3400 1800);
DISPLAY 0.872340 (-3400 1800);
PAINT GREEN (-3400 1800);
DISPLAY INVISIBLE (-3400 1800);
FORCEPROP 1 LAST HDL_TAP TRUE
J 0
(-3075 1625);
DISPLAY 0.872340 (-3075 1625);
DISPLAY INVISIBLE (-3075 1625);
FORCEPROP 1 LAST PATH I242
J 0
(-3402 1750);
DISPLAY 0.872340 (-3402 1750);
PAINT GREEN (-3402 1750);
DISPLAY INVISIBLE (-3402 1750);
FORCEADD TAP..1
(-3400 1650);
FORCEPROP 3 LASTPIN (-3450 1650) SIG_NAME M_E_CPU0_SB_CB<7>
J 0
(-3440 1660);
DISPLAY 0.659574 (-3440 1660);
PAINT MONO (-3440 1660);
DISPLAY INVISIBLE (-3440 1660);
FORCEPROP 1 LASTPIN (-3450 1650) BN 7
J 0
(-3462 1658);
DISPLAY 0.489362 (-3462 1658);
PAINT GREEN (-3462 1658);
FORCEPROP 2 LAST CDS_LIB mstr_standard
J 2
(-3400 1650);
DISPLAY 0.723404 (-3400 1650);
PAINT MONO (-3400 1650);
DISPLAY INVISIBLE (-3400 1650);
FORCEPROP 1 LAST BODY_TYPE PLUMBING
J 0
(-3400 1700);
DISPLAY 0.872340 (-3400 1700);
PAINT GREEN (-3400 1700);
DISPLAY INVISIBLE (-3400 1700);
FORCEPROP 1 LAST HDL_TAP TRUE
J 0
(-3075 1525);
DISPLAY 0.872340 (-3075 1525);
DISPLAY INVISIBLE (-3075 1525);
FORCEPROP 1 LAST PATH I243
J 0
(-3402 1650);
DISPLAY 0.872340 (-3402 1650);
PAINT GREEN (-3402 1650);
DISPLAY INVISIBLE (-3402 1650);
FORCEADD TAP..1
R 2
(-5825 6050);
FORCEPROP 3 LASTPIN (-5775 6050) SIG_NAME M_E_CPU0_SA_DQS_DP<0>
J 0
(-5765 6060);
DISPLAY 0.659574 (-5765 6060);
PAINT MONO (-5765 6060);
DISPLAY INVISIBLE (-5765 6060);
FORCEPROP 1 LASTPIN (-5775 6050) BN 0
J 2
(-5763 6058);
DISPLAY 0.489362 (-5763 6058);
PAINT GREEN (-5763 6058);
FORCEPROP 2 LAST CDS_LIB mstr_standard
J 2
(-5825 6050);
DISPLAY 0.723404 (-5825 6050);
PAINT MONO (-5825 6050);
DISPLAY INVISIBLE (-5825 6050);
FORCEPROP 1 LAST BODY_TYPE PLUMBING
J 2
(-5825 6100);
DISPLAY 0.872340 (-5825 6100);
PAINT GREEN (-5825 6100);
DISPLAY INVISIBLE (-5825 6100);
FORCEPROP 1 LAST HDL_TAP TRUE
J 2
(-6150 5925);
DISPLAY 0.872340 (-6150 5925);
DISPLAY INVISIBLE (-6150 5925);
FORCEPROP 1 LAST PATH I244
J 2
(-5823 6050);
DISPLAY 0.872340 (-5823 6050);
PAINT GREEN (-5823 6050);
DISPLAY INVISIBLE (-5823 6050);
FORCEADD TAP..1
R 2
(-5825 5950);
FORCEPROP 3 LASTPIN (-5775 5950) SIG_NAME M_E_CPU0_SA_DQS_DP<1>
J 0
(-5765 5960);
DISPLAY 0.659574 (-5765 5960);
PAINT MONO (-5765 5960);
DISPLAY INVISIBLE (-5765 5960);
FORCEPROP 1 LASTPIN (-5775 5950) BN 1
J 2
(-5763 5958);
DISPLAY 0.489362 (-5763 5958);
PAINT GREEN (-5763 5958);
FORCEPROP 2 LAST CDS_LIB mstr_standard
J 2
(-5825 5950);
DISPLAY 0.723404 (-5825 5950);
PAINT MONO (-5825 5950);
DISPLAY INVISIBLE (-5825 5950);
FORCEPROP 1 LAST BODY_TYPE PLUMBING
J 2
(-5825 6000);
DISPLAY 0.872340 (-5825 6000);
PAINT GREEN (-5825 6000);
DISPLAY INVISIBLE (-5825 6000);
FORCEPROP 1 LAST HDL_TAP TRUE
J 2
(-6150 5825);
DISPLAY 0.872340 (-6150 5825);
DISPLAY INVISIBLE (-6150 5825);
FORCEPROP 1 LAST PATH I245
J 2
(-5823 5950);
DISPLAY 0.872340 (-5823 5950);
PAINT GREEN (-5823 5950);
DISPLAY INVISIBLE (-5823 5950);
FORCEADD TAP..1
R 2
(-5825 5750);
FORCEPROP 3 LASTPIN (-5775 5750) SIG_NAME M_E_CPU0_SA_DQS_DP<3>
J 0
(-5765 5760);
DISPLAY 0.659574 (-5765 5760);
PAINT MONO (-5765 5760);
DISPLAY INVISIBLE (-5765 5760);
FORCEPROP 1 LASTPIN (-5775 5750) BN 3
J 2
(-5763 5758);
DISPLAY 0.489362 (-5763 5758);
PAINT GREEN (-5763 5758);
FORCEPROP 2 LAST CDS_LIB mstr_standard
J 2
(-5825 5750);
DISPLAY 0.723404 (-5825 5750);
PAINT MONO (-5825 5750);
DISPLAY INVISIBLE (-5825 5750);
FORCEPROP 1 LAST BODY_TYPE PLUMBING
J 2
(-5825 5800);
DISPLAY 0.872340 (-5825 5800);
PAINT GREEN (-5825 5800);
DISPLAY INVISIBLE (-5825 5800);
FORCEPROP 1 LAST HDL_TAP TRUE
J 2
(-6150 5625);
DISPLAY 0.872340 (-6150 5625);
DISPLAY INVISIBLE (-6150 5625);
FORCEPROP 1 LAST PATH I246
J 2
(-5823 5750);
DISPLAY 0.872340 (-5823 5750);
PAINT GREEN (-5823 5750);
DISPLAY INVISIBLE (-5823 5750);
FORCEADD TAP..1
R 2
(-5825 5850);
FORCEPROP 3 LASTPIN (-5775 5850) SIG_NAME M_E_CPU0_SA_DQS_DP<2>
J 0
(-5765 5860);
DISPLAY 0.659574 (-5765 5860);
PAINT MONO (-5765 5860);
DISPLAY INVISIBLE (-5765 5860);
FORCEPROP 1 LASTPIN (-5775 5850) BN 2
J 2
(-5763 5858);
DISPLAY 0.489362 (-5763 5858);
PAINT GREEN (-5763 5858);
FORCEPROP 2 LAST CDS_LIB mstr_standard
J 2
(-5825 5850);
DISPLAY 0.723404 (-5825 5850);
PAINT MONO (-5825 5850);
DISPLAY INVISIBLE (-5825 5850);
FORCEPROP 1 LAST BODY_TYPE PLUMBING
J 2
(-5825 5900);
DISPLAY 0.872340 (-5825 5900);
PAINT GREEN (-5825 5900);
DISPLAY INVISIBLE (-5825 5900);
FORCEPROP 1 LAST HDL_TAP TRUE
J 2
(-6150 5725);
DISPLAY 0.872340 (-6150 5725);
DISPLAY INVISIBLE (-6150 5725);
FORCEPROP 1 LAST PATH I247
J 2
(-5823 5850);
DISPLAY 0.872340 (-5823 5850);
PAINT GREEN (-5823 5850);
DISPLAY INVISIBLE (-5823 5850);
FORCEADD TAP..1
R 2
(-5825 5650);
FORCEPROP 3 LASTPIN (-5775 5650) SIG_NAME M_E_CPU0_SA_DQS_DP<4>
J 0
(-5765 5660);
DISPLAY 0.659574 (-5765 5660);
PAINT MONO (-5765 5660);
DISPLAY INVISIBLE (-5765 5660);
FORCEPROP 1 LASTPIN (-5775 5650) BN 4
J 2
(-5763 5658);
DISPLAY 0.489362 (-5763 5658);
PAINT GREEN (-5763 5658);
FORCEPROP 2 LAST CDS_LIB mstr_standard
J 2
(-5825 5650);
DISPLAY 0.723404 (-5825 5650);
PAINT MONO (-5825 5650);
DISPLAY INVISIBLE (-5825 5650);
FORCEPROP 1 LAST BODY_TYPE PLUMBING
J 2
(-5825 5700);
DISPLAY 0.872340 (-5825 5700);
PAINT GREEN (-5825 5700);
DISPLAY INVISIBLE (-5825 5700);
FORCEPROP 1 LAST HDL_TAP TRUE
J 2
(-6150 5525);
DISPLAY 0.872340 (-6150 5525);
DISPLAY INVISIBLE (-6150 5525);
FORCEPROP 1 LAST PATH I248
J 2
(-5823 5650);
DISPLAY 0.872340 (-5823 5650);
PAINT GREEN (-5823 5650);
DISPLAY INVISIBLE (-5823 5650);
FORCEADD TAP..1
R 2
(-6025 6000);
FORCEPROP 3 LASTPIN (-5975 6000) SIG_NAME M_E_CPU0_SA_DQS_DN<0>
J 0
(-5965 6010);
DISPLAY 0.659574 (-5965 6010);
PAINT MONO (-5965 6010);
DISPLAY INVISIBLE (-5965 6010);
FORCEPROP 1 LASTPIN (-5975 6000) BN 0
J 2
(-5963 6008);
DISPLAY 0.489362 (-5963 6008);
PAINT GREEN (-5963 6008);
FORCEPROP 2 LAST CDS_LIB mstr_standard
J 2
(-6025 6000);
DISPLAY 0.723404 (-6025 6000);
PAINT MONO (-6025 6000);
DISPLAY INVISIBLE (-6025 6000);
FORCEPROP 1 LAST BODY_TYPE PLUMBING
J 2
(-6025 6050);
DISPLAY 0.872340 (-6025 6050);
PAINT GREEN (-6025 6050);
DISPLAY INVISIBLE (-6025 6050);
FORCEPROP 1 LAST HDL_TAP TRUE
J 2
(-6350 5875);
DISPLAY 0.872340 (-6350 5875);
DISPLAY INVISIBLE (-6350 5875);
FORCEPROP 1 LAST PATH I249
J 2
(-6023 6000);
DISPLAY 0.872340 (-6023 6000);
PAINT GREEN (-6023 6000);
DISPLAY INVISIBLE (-6023 6000);
FORCEADD TAP..1
R 2
(-6025 5900);
FORCEPROP 3 LASTPIN (-5975 5900) SIG_NAME M_E_CPU0_SA_DQS_DN<1>
J 0
(-5965 5910);
DISPLAY 0.659574 (-5965 5910);
PAINT MONO (-5965 5910);
DISPLAY INVISIBLE (-5965 5910);
FORCEPROP 1 LASTPIN (-5975 5900) BN 1
J 2
(-5963 5908);
DISPLAY 0.489362 (-5963 5908);
PAINT GREEN (-5963 5908);
FORCEPROP 2 LAST CDS_LIB mstr_standard
J 2
(-6025 5900);
DISPLAY 0.723404 (-6025 5900);
PAINT MONO (-6025 5900);
DISPLAY INVISIBLE (-6025 5900);
FORCEPROP 1 LAST BODY_TYPE PLUMBING
J 2
(-6025 5950);
DISPLAY 0.872340 (-6025 5950);
PAINT GREEN (-6025 5950);
DISPLAY INVISIBLE (-6025 5950);
FORCEPROP 1 LAST HDL_TAP TRUE
J 2
(-6350 5775);
DISPLAY 0.872340 (-6350 5775);
DISPLAY INVISIBLE (-6350 5775);
FORCEPROP 1 LAST PATH I250
J 2
(-6023 5900);
DISPLAY 0.872340 (-6023 5900);
PAINT GREEN (-6023 5900);
DISPLAY INVISIBLE (-6023 5900);
FORCEADD TAP..1
R 2
(-6025 5800);
FORCEPROP 3 LASTPIN (-5975 5800) SIG_NAME M_E_CPU0_SA_DQS_DN<2>
J 0
(-5965 5810);
DISPLAY 0.659574 (-5965 5810);
PAINT MONO (-5965 5810);
DISPLAY INVISIBLE (-5965 5810);
FORCEPROP 1 LASTPIN (-5975 5800) BN 2
J 2
(-5963 5808);
DISPLAY 0.489362 (-5963 5808);
PAINT GREEN (-5963 5808);
FORCEPROP 2 LAST CDS_LIB mstr_standard
J 2
(-6025 5800);
DISPLAY 0.723404 (-6025 5800);
PAINT MONO (-6025 5800);
DISPLAY INVISIBLE (-6025 5800);
FORCEPROP 1 LAST BODY_TYPE PLUMBING
J 2
(-6025 5850);
DISPLAY 0.872340 (-6025 5850);
PAINT GREEN (-6025 5850);
DISPLAY INVISIBLE (-6025 5850);
FORCEPROP 1 LAST HDL_TAP TRUE
J 2
(-6350 5675);
DISPLAY 0.872340 (-6350 5675);
DISPLAY INVISIBLE (-6350 5675);
FORCEPROP 1 LAST PATH I251
J 2
(-6023 5800);
DISPLAY 0.872340 (-6023 5800);
PAINT GREEN (-6023 5800);
DISPLAY INVISIBLE (-6023 5800);
FORCEADD TAP..1
R 2
(-6025 5700);
FORCEPROP 3 LASTPIN (-5975 5700) SIG_NAME M_E_CPU0_SA_DQS_DN<3>
J 0
(-5965 5710);
DISPLAY 0.659574 (-5965 5710);
PAINT MONO (-5965 5710);
DISPLAY INVISIBLE (-5965 5710);
FORCEPROP 1 LASTPIN (-5975 5700) BN 3
J 2
(-5963 5708);
DISPLAY 0.489362 (-5963 5708);
PAINT GREEN (-5963 5708);
FORCEPROP 2 LAST CDS_LIB mstr_standard
J 2
(-6025 5700);
DISPLAY 0.723404 (-6025 5700);
PAINT MONO (-6025 5700);
DISPLAY INVISIBLE (-6025 5700);
FORCEPROP 1 LAST BODY_TYPE PLUMBING
J 2
(-6025 5750);
DISPLAY 0.872340 (-6025 5750);
PAINT GREEN (-6025 5750);
DISPLAY INVISIBLE (-6025 5750);
FORCEPROP 1 LAST HDL_TAP TRUE
J 2
(-6350 5575);
DISPLAY 0.872340 (-6350 5575);
DISPLAY INVISIBLE (-6350 5575);
FORCEPROP 1 LAST PATH I252
J 2
(-6023 5700);
DISPLAY 0.872340 (-6023 5700);
PAINT GREEN (-6023 5700);
DISPLAY INVISIBLE (-6023 5700);
FORCEADD TAP..1
R 2
(-5825 5550);
FORCEPROP 3 LASTPIN (-5775 5550) SIG_NAME M_E_CPU0_SA_DQS_DP<5>
J 0
(-5765 5560);
DISPLAY 0.659574 (-5765 5560);
PAINT MONO (-5765 5560);
DISPLAY INVISIBLE (-5765 5560);
FORCEPROP 1 LASTPIN (-5775 5550) BN 5
J 2
(-5763 5558);
DISPLAY 0.489362 (-5763 5558);
PAINT GREEN (-5763 5558);
FORCEPROP 2 LAST CDS_LIB mstr_standard
J 2
(-5825 5550);
DISPLAY 0.723404 (-5825 5550);
PAINT MONO (-5825 5550);
DISPLAY INVISIBLE (-5825 5550);
FORCEPROP 1 LAST BODY_TYPE PLUMBING
J 2
(-5825 5600);
DISPLAY 0.872340 (-5825 5600);
PAINT GREEN (-5825 5600);
DISPLAY INVISIBLE (-5825 5600);
FORCEPROP 1 LAST HDL_TAP TRUE
J 2
(-6150 5425);
DISPLAY 0.872340 (-6150 5425);
DISPLAY INVISIBLE (-6150 5425);
FORCEPROP 1 LAST PATH I253
J 2
(-5823 5550);
DISPLAY 0.872340 (-5823 5550);
PAINT GREEN (-5823 5550);
DISPLAY INVISIBLE (-5823 5550);
FORCEADD TAP..1
R 2
(-5825 5450);
FORCEPROP 3 LASTPIN (-5775 5450) SIG_NAME M_E_CPU0_SA_DQS_DP<6>
J 0
(-5765 5460);
DISPLAY 0.659574 (-5765 5460);
PAINT MONO (-5765 5460);
DISPLAY INVISIBLE (-5765 5460);
FORCEPROP 1 LASTPIN (-5775 5450) BN 6
J 2
(-5763 5458);
DISPLAY 0.489362 (-5763 5458);
PAINT GREEN (-5763 5458);
FORCEPROP 2 LAST CDS_LIB mstr_standard
J 2
(-5825 5450);
DISPLAY 0.723404 (-5825 5450);
PAINT MONO (-5825 5450);
DISPLAY INVISIBLE (-5825 5450);
FORCEPROP 1 LAST BODY_TYPE PLUMBING
J 2
(-5825 5500);
DISPLAY 0.872340 (-5825 5500);
PAINT GREEN (-5825 5500);
DISPLAY INVISIBLE (-5825 5500);
FORCEPROP 1 LAST HDL_TAP TRUE
J 2
(-6150 5325);
DISPLAY 0.872340 (-6150 5325);
DISPLAY INVISIBLE (-6150 5325);
FORCEPROP 1 LAST PATH I254
J 2
(-5823 5450);
DISPLAY 0.872340 (-5823 5450);
PAINT GREEN (-5823 5450);
DISPLAY INVISIBLE (-5823 5450);
FORCEADD TAP..1
R 2
(-5825 5250);
FORCEPROP 3 LASTPIN (-5775 5250) SIG_NAME M_E_CPU0_SA_DQS_DP<8>
J 0
(-5765 5260);
DISPLAY 0.659574 (-5765 5260);
PAINT MONO (-5765 5260);
DISPLAY INVISIBLE (-5765 5260);
FORCEPROP 1 LASTPIN (-5775 5250) BN 8
J 2
(-5763 5258);
DISPLAY 0.489362 (-5763 5258);
PAINT GREEN (-5763 5258);
FORCEPROP 2 LAST CDS_LIB mstr_standard
J 2
(-5825 5250);
DISPLAY 0.723404 (-5825 5250);
PAINT MONO (-5825 5250);
DISPLAY INVISIBLE (-5825 5250);
FORCEPROP 1 LAST BODY_TYPE PLUMBING
J 2
(-5825 5300);
DISPLAY 0.872340 (-5825 5300);
PAINT GREEN (-5825 5300);
DISPLAY INVISIBLE (-5825 5300);
FORCEPROP 1 LAST HDL_TAP TRUE
J 2
(-6150 5125);
DISPLAY 0.872340 (-6150 5125);
DISPLAY INVISIBLE (-6150 5125);
FORCEPROP 1 LAST PATH I255
J 2
(-5823 5250);
DISPLAY 0.872340 (-5823 5250);
PAINT GREEN (-5823 5250);
DISPLAY INVISIBLE (-5823 5250);
FORCEADD TAP..1
R 2
(-5825 5350);
FORCEPROP 3 LASTPIN (-5775 5350) SIG_NAME M_E_CPU0_SA_DQS_DP<7>
J 0
(-5765 5360);
DISPLAY 0.659574 (-5765 5360);
PAINT MONO (-5765 5360);
DISPLAY INVISIBLE (-5765 5360);
FORCEPROP 1 LASTPIN (-5775 5350) BN 7
J 2
(-5763 5358);
DISPLAY 0.489362 (-5763 5358);
PAINT GREEN (-5763 5358);
FORCEPROP 2 LAST CDS_LIB mstr_standard
J 2
(-5825 5350);
DISPLAY 0.723404 (-5825 5350);
PAINT MONO (-5825 5350);
DISPLAY INVISIBLE (-5825 5350);
FORCEPROP 1 LAST BODY_TYPE PLUMBING
J 2
(-5825 5400);
DISPLAY 0.872340 (-5825 5400);
PAINT GREEN (-5825 5400);
DISPLAY INVISIBLE (-5825 5400);
FORCEPROP 1 LAST HDL_TAP TRUE
J 2
(-6150 5225);
DISPLAY 0.872340 (-6150 5225);
DISPLAY INVISIBLE (-6150 5225);
FORCEPROP 1 LAST PATH I256
J 2
(-5823 5350);
DISPLAY 0.872340 (-5823 5350);
PAINT GREEN (-5823 5350);
DISPLAY INVISIBLE (-5823 5350);
FORCEADD TAP..1
R 2
(-5825 5150);
FORCEPROP 3 LASTPIN (-5775 5150) SIG_NAME M_E_CPU0_SA_DQS_DP<9>
J 0
(-5765 5160);
DISPLAY 0.659574 (-5765 5160);
PAINT MONO (-5765 5160);
DISPLAY INVISIBLE (-5765 5160);
FORCEPROP 1 LASTPIN (-5775 5150) BN 9
J 2
(-5763 5158);
DISPLAY 0.489362 (-5763 5158);
PAINT GREEN (-5763 5158);
FORCEPROP 2 LAST CDS_LIB mstr_standard
J 2
(-5825 5150);
DISPLAY 0.723404 (-5825 5150);
PAINT MONO (-5825 5150);
DISPLAY INVISIBLE (-5825 5150);
FORCEPROP 1 LAST BODY_TYPE PLUMBING
J 2
(-5825 5200);
DISPLAY 0.872340 (-5825 5200);
PAINT GREEN (-5825 5200);
DISPLAY INVISIBLE (-5825 5200);
FORCEPROP 1 LAST HDL_TAP TRUE
J 2
(-6150 5025);
DISPLAY 0.872340 (-6150 5025);
DISPLAY INVISIBLE (-6150 5025);
FORCEPROP 1 LAST PATH I257
J 2
(-5823 5150);
DISPLAY 0.872340 (-5823 5150);
PAINT GREEN (-5823 5150);
DISPLAY INVISIBLE (-5823 5150);
FORCEADD TAP..1
R 2
(-6025 5600);
FORCEPROP 3 LASTPIN (-5975 5600) SIG_NAME M_E_CPU0_SA_DQS_DN<4>
J 0
(-5965 5610);
DISPLAY 0.659574 (-5965 5610);
PAINT MONO (-5965 5610);
DISPLAY INVISIBLE (-5965 5610);
FORCEPROP 1 LASTPIN (-5975 5600) BN 4
J 2
(-5963 5608);
DISPLAY 0.489362 (-5963 5608);
PAINT GREEN (-5963 5608);
FORCEPROP 2 LAST CDS_LIB mstr_standard
J 2
(-6025 5600);
DISPLAY 0.723404 (-6025 5600);
PAINT MONO (-6025 5600);
DISPLAY INVISIBLE (-6025 5600);
FORCEPROP 1 LAST BODY_TYPE PLUMBING
J 2
(-6025 5650);
DISPLAY 0.872340 (-6025 5650);
PAINT GREEN (-6025 5650);
DISPLAY INVISIBLE (-6025 5650);
FORCEPROP 1 LAST HDL_TAP TRUE
J 2
(-6350 5475);
DISPLAY 0.872340 (-6350 5475);
DISPLAY INVISIBLE (-6350 5475);
FORCEPROP 1 LAST PATH I258
J 2
(-6023 5600);
DISPLAY 0.872340 (-6023 5600);
PAINT GREEN (-6023 5600);
DISPLAY INVISIBLE (-6023 5600);
FORCEADD TAP..1
R 2
(-6025 5500);
FORCEPROP 3 LASTPIN (-5975 5500) SIG_NAME M_E_CPU0_SA_DQS_DN<5>
J 0
(-5965 5510);
DISPLAY 0.659574 (-5965 5510);
PAINT MONO (-5965 5510);
DISPLAY INVISIBLE (-5965 5510);
FORCEPROP 1 LASTPIN (-5975 5500) BN 5
J 2
(-5963 5508);
DISPLAY 0.489362 (-5963 5508);
PAINT GREEN (-5963 5508);
FORCEPROP 2 LAST CDS_LIB mstr_standard
J 2
(-6025 5500);
DISPLAY 0.723404 (-6025 5500);
PAINT MONO (-6025 5500);
DISPLAY INVISIBLE (-6025 5500);
FORCEPROP 1 LAST BODY_TYPE PLUMBING
J 2
(-6025 5550);
DISPLAY 0.872340 (-6025 5550);
PAINT GREEN (-6025 5550);
DISPLAY INVISIBLE (-6025 5550);
FORCEPROP 1 LAST HDL_TAP TRUE
J 2
(-6350 5375);
DISPLAY 0.872340 (-6350 5375);
DISPLAY INVISIBLE (-6350 5375);
FORCEPROP 1 LAST PATH I259
J 2
(-6023 5500);
DISPLAY 0.872340 (-6023 5500);
PAINT GREEN (-6023 5500);
DISPLAY INVISIBLE (-6023 5500);
FORCEADD TAP..1
R 2
(-6025 5400);
FORCEPROP 3 LASTPIN (-5975 5400) SIG_NAME M_E_CPU0_SA_DQS_DN<6>
J 0
(-5965 5410);
DISPLAY 0.659574 (-5965 5410);
PAINT MONO (-5965 5410);
DISPLAY INVISIBLE (-5965 5410);
FORCEPROP 1 LASTPIN (-5975 5400) BN 6
J 2
(-5963 5408);
DISPLAY 0.489362 (-5963 5408);
PAINT GREEN (-5963 5408);
FORCEPROP 2 LAST CDS_LIB mstr_standard
J 2
(-6025 5400);
DISPLAY 0.723404 (-6025 5400);
PAINT MONO (-6025 5400);
DISPLAY INVISIBLE (-6025 5400);
FORCEPROP 1 LAST BODY_TYPE PLUMBING
J 2
(-6025 5450);
DISPLAY 0.872340 (-6025 5450);
PAINT GREEN (-6025 5450);
DISPLAY INVISIBLE (-6025 5450);
FORCEPROP 1 LAST HDL_TAP TRUE
J 2
(-6350 5275);
DISPLAY 0.872340 (-6350 5275);
DISPLAY INVISIBLE (-6350 5275);
FORCEPROP 1 LAST PATH I260
J 2
(-6023 5400);
DISPLAY 0.872340 (-6023 5400);
PAINT GREEN (-6023 5400);
DISPLAY INVISIBLE (-6023 5400);
FORCEADD TAP..1
R 2
(-6025 5300);
FORCEPROP 3 LASTPIN (-5975 5300) SIG_NAME M_E_CPU0_SA_DQS_DN<7>
J 0
(-5965 5310);
DISPLAY 0.659574 (-5965 5310);
PAINT MONO (-5965 5310);
DISPLAY INVISIBLE (-5965 5310);
FORCEPROP 1 LASTPIN (-5975 5300) BN 7
J 2
(-5963 5308);
DISPLAY 0.489362 (-5963 5308);
PAINT GREEN (-5963 5308);
FORCEPROP 2 LAST CDS_LIB mstr_standard
J 2
(-6025 5300);
DISPLAY 0.723404 (-6025 5300);
PAINT MONO (-6025 5300);
DISPLAY INVISIBLE (-6025 5300);
FORCEPROP 1 LAST BODY_TYPE PLUMBING
J 2
(-6025 5350);
DISPLAY 0.872340 (-6025 5350);
PAINT GREEN (-6025 5350);
DISPLAY INVISIBLE (-6025 5350);
FORCEPROP 1 LAST HDL_TAP TRUE
J 2
(-6350 5175);
DISPLAY 0.872340 (-6350 5175);
DISPLAY INVISIBLE (-6350 5175);
FORCEPROP 1 LAST PATH I261
J 2
(-6023 5300);
DISPLAY 0.872340 (-6023 5300);
PAINT GREEN (-6023 5300);
DISPLAY INVISIBLE (-6023 5300);
FORCEADD TAP..1
R 2
(-6025 5200);
FORCEPROP 3 LASTPIN (-5975 5200) SIG_NAME M_E_CPU0_SA_DQS_DN<8>
J 0
(-5965 5210);
DISPLAY 0.659574 (-5965 5210);
PAINT MONO (-5965 5210);
DISPLAY INVISIBLE (-5965 5210);
FORCEPROP 1 LASTPIN (-5975 5200) BN 8
J 2
(-5963 5208);
DISPLAY 0.489362 (-5963 5208);
PAINT GREEN (-5963 5208);
FORCEPROP 2 LAST CDS_LIB mstr_standard
J 2
(-6025 5200);
DISPLAY 0.723404 (-6025 5200);
PAINT MONO (-6025 5200);
DISPLAY INVISIBLE (-6025 5200);
FORCEPROP 1 LAST BODY_TYPE PLUMBING
J 2
(-6025 5250);
DISPLAY 0.872340 (-6025 5250);
PAINT GREEN (-6025 5250);
DISPLAY INVISIBLE (-6025 5250);
FORCEPROP 1 LAST HDL_TAP TRUE
J 2
(-6350 5075);
DISPLAY 0.872340 (-6350 5075);
DISPLAY INVISIBLE (-6350 5075);
FORCEPROP 1 LAST PATH I262
J 2
(-6023 5200);
DISPLAY 0.872340 (-6023 5200);
PAINT GREEN (-6023 5200);
DISPLAY INVISIBLE (-6023 5200);
FORCEADD TAP..1
R 2
(-5825 4900);
FORCEPROP 3 LASTPIN (-5775 4900) SIG_NAME M_E_CPU0_SB_DQS_DP<1>
J 0
(-5765 4910);
DISPLAY 0.659574 (-5765 4910);
PAINT MONO (-5765 4910);
DISPLAY INVISIBLE (-5765 4910);
FORCEPROP 1 LASTPIN (-5775 4900) BN 1
J 2
(-5763 4908);
DISPLAY 0.489362 (-5763 4908);
PAINT GREEN (-5763 4908);
FORCEPROP 2 LAST CDS_LIB mstr_standard
J 2
(-5825 4900);
DISPLAY 0.723404 (-5825 4900);
PAINT MONO (-5825 4900);
DISPLAY INVISIBLE (-5825 4900);
FORCEPROP 1 LAST BODY_TYPE PLUMBING
J 2
(-5825 4950);
DISPLAY 0.872340 (-5825 4950);
PAINT GREEN (-5825 4950);
DISPLAY INVISIBLE (-5825 4950);
FORCEPROP 1 LAST HDL_TAP TRUE
J 2
(-6150 4775);
DISPLAY 0.872340 (-6150 4775);
DISPLAY INVISIBLE (-6150 4775);
FORCEPROP 1 LAST PATH I263
J 2
(-5823 4900);
DISPLAY 0.872340 (-5823 4900);
PAINT GREEN (-5823 4900);
DISPLAY INVISIBLE (-5823 4900);
FORCEADD TAP..1
R 2
(-5825 5000);
FORCEPROP 3 LASTPIN (-5775 5000) SIG_NAME M_E_CPU0_SB_DQS_DP<0>
J 0
(-5765 5010);
DISPLAY 0.659574 (-5765 5010);
PAINT MONO (-5765 5010);
DISPLAY INVISIBLE (-5765 5010);
FORCEPROP 1 LASTPIN (-5775 5000) BN 0
J 2
(-5763 5008);
DISPLAY 0.489362 (-5763 5008);
PAINT GREEN (-5763 5008);
FORCEPROP 2 LAST CDS_LIB mstr_standard
J 2
(-5825 5000);
DISPLAY 0.723404 (-5825 5000);
PAINT MONO (-5825 5000);
DISPLAY INVISIBLE (-5825 5000);
FORCEPROP 1 LAST BODY_TYPE PLUMBING
J 2
(-5825 5050);
DISPLAY 0.872340 (-5825 5050);
PAINT GREEN (-5825 5050);
DISPLAY INVISIBLE (-5825 5050);
FORCEPROP 1 LAST HDL_TAP TRUE
J 2
(-6150 4875);
DISPLAY 0.872340 (-6150 4875);
DISPLAY INVISIBLE (-6150 4875);
FORCEPROP 1 LAST PATH I264
J 2
(-5823 5000);
DISPLAY 0.872340 (-5823 5000);
PAINT GREEN (-5823 5000);
DISPLAY INVISIBLE (-5823 5000);
FORCEADD TAP..1
R 2
(-5825 4800);
FORCEPROP 3 LASTPIN (-5775 4800) SIG_NAME M_E_CPU0_SB_DQS_DP<2>
J 0
(-5765 4810);
DISPLAY 0.659574 (-5765 4810);
PAINT MONO (-5765 4810);
DISPLAY INVISIBLE (-5765 4810);
FORCEPROP 1 LASTPIN (-5775 4800) BN 2
J 2
(-5763 4808);
DISPLAY 0.489362 (-5763 4808);
PAINT GREEN (-5763 4808);
FORCEPROP 2 LAST CDS_LIB mstr_standard
J 2
(-5825 4800);
DISPLAY 0.723404 (-5825 4800);
PAINT MONO (-5825 4800);
DISPLAY INVISIBLE (-5825 4800);
FORCEPROP 1 LAST BODY_TYPE PLUMBING
J 2
(-5825 4850);
DISPLAY 0.872340 (-5825 4850);
PAINT GREEN (-5825 4850);
DISPLAY INVISIBLE (-5825 4850);
FORCEPROP 1 LAST HDL_TAP TRUE
J 2
(-6150 4675);
DISPLAY 0.872340 (-6150 4675);
DISPLAY INVISIBLE (-6150 4675);
FORCEPROP 1 LAST PATH I265
J 2
(-5823 4800);
DISPLAY 0.872340 (-5823 4800);
PAINT GREEN (-5823 4800);
DISPLAY INVISIBLE (-5823 4800);
FORCEADD TAP..1
R 2
(-5825 4700);
FORCEPROP 3 LASTPIN (-5775 4700) SIG_NAME M_E_CPU0_SB_DQS_DP<3>
J 0
(-5765 4710);
DISPLAY 0.659574 (-5765 4710);
PAINT MONO (-5765 4710);
DISPLAY INVISIBLE (-5765 4710);
FORCEPROP 1 LASTPIN (-5775 4700) BN 3
J 2
(-5763 4708);
DISPLAY 0.489362 (-5763 4708);
PAINT GREEN (-5763 4708);
FORCEPROP 2 LAST CDS_LIB mstr_standard
J 2
(-5825 4700);
DISPLAY 0.723404 (-5825 4700);
PAINT MONO (-5825 4700);
DISPLAY INVISIBLE (-5825 4700);
FORCEPROP 1 LAST BODY_TYPE PLUMBING
J 2
(-5825 4750);
DISPLAY 0.872340 (-5825 4750);
PAINT GREEN (-5825 4750);
DISPLAY INVISIBLE (-5825 4750);
FORCEPROP 1 LAST HDL_TAP TRUE
J 2
(-6150 4575);
DISPLAY 0.872340 (-6150 4575);
DISPLAY INVISIBLE (-6150 4575);
FORCEPROP 1 LAST PATH I266
J 2
(-5823 4700);
DISPLAY 0.872340 (-5823 4700);
PAINT GREEN (-5823 4700);
DISPLAY INVISIBLE (-5823 4700);
FORCEADD TAP..1
R 2
(-6025 4950);
FORCEPROP 3 LASTPIN (-5975 4950) SIG_NAME M_E_CPU0_SB_DQS_DN<0>
J 0
(-5965 4960);
DISPLAY 0.659574 (-5965 4960);
PAINT MONO (-5965 4960);
DISPLAY INVISIBLE (-5965 4960);
FORCEPROP 1 LASTPIN (-5975 4950) BN 0
J 2
(-5963 4958);
DISPLAY 0.489362 (-5963 4958);
PAINT GREEN (-5963 4958);
FORCEPROP 2 LAST CDS_LIB mstr_standard
J 2
(-6025 4950);
DISPLAY 0.723404 (-6025 4950);
PAINT MONO (-6025 4950);
DISPLAY INVISIBLE (-6025 4950);
FORCEPROP 1 LAST BODY_TYPE PLUMBING
J 2
(-6025 5000);
DISPLAY 0.872340 (-6025 5000);
PAINT GREEN (-6025 5000);
DISPLAY INVISIBLE (-6025 5000);
FORCEPROP 1 LAST HDL_TAP TRUE
J 2
(-6350 4825);
DISPLAY 0.872340 (-6350 4825);
DISPLAY INVISIBLE (-6350 4825);
FORCEPROP 1 LAST PATH I267
J 2
(-6023 4950);
DISPLAY 0.872340 (-6023 4950);
PAINT GREEN (-6023 4950);
DISPLAY INVISIBLE (-6023 4950);
FORCEADD TAP..1
R 2
(-6025 5100);
FORCEPROP 3 LASTPIN (-5975 5100) SIG_NAME M_E_CPU0_SA_DQS_DN<9>
J 0
(-5965 5110);
DISPLAY 0.659574 (-5965 5110);
PAINT MONO (-5965 5110);
DISPLAY INVISIBLE (-5965 5110);
FORCEPROP 1 LASTPIN (-5975 5100) BN 9
J 2
(-5963 5108);
DISPLAY 0.489362 (-5963 5108);
PAINT GREEN (-5963 5108);
FORCEPROP 2 LAST CDS_LIB mstr_standard
J 2
(-6025 5100);
DISPLAY 0.723404 (-6025 5100);
PAINT MONO (-6025 5100);
DISPLAY INVISIBLE (-6025 5100);
FORCEPROP 1 LAST BODY_TYPE PLUMBING
J 2
(-6025 5150);
DISPLAY 0.872340 (-6025 5150);
PAINT GREEN (-6025 5150);
DISPLAY INVISIBLE (-6025 5150);
FORCEPROP 1 LAST HDL_TAP TRUE
J 2
(-6350 4975);
DISPLAY 0.872340 (-6350 4975);
DISPLAY INVISIBLE (-6350 4975);
FORCEPROP 1 LAST PATH I268
J 2
(-6023 5100);
DISPLAY 0.872340 (-6023 5100);
PAINT GREEN (-6023 5100);
DISPLAY INVISIBLE (-6023 5100);
FORCEADD TAP..1
R 2
(-6025 4850);
FORCEPROP 3 LASTPIN (-5975 4850) SIG_NAME M_E_CPU0_SB_DQS_DN<1>
J 0
(-5965 4860);
DISPLAY 0.659574 (-5965 4860);
PAINT MONO (-5965 4860);
DISPLAY INVISIBLE (-5965 4860);
FORCEPROP 1 LASTPIN (-5975 4850) BN 1
J 2
(-5963 4858);
DISPLAY 0.489362 (-5963 4858);
PAINT GREEN (-5963 4858);
FORCEPROP 2 LAST CDS_LIB mstr_standard
J 2
(-6025 4850);
DISPLAY 0.723404 (-6025 4850);
PAINT MONO (-6025 4850);
DISPLAY INVISIBLE (-6025 4850);
FORCEPROP 1 LAST BODY_TYPE PLUMBING
J 2
(-6025 4900);
DISPLAY 0.872340 (-6025 4900);
PAINT GREEN (-6025 4900);
DISPLAY INVISIBLE (-6025 4900);
FORCEPROP 1 LAST HDL_TAP TRUE
J 2
(-6350 4725);
DISPLAY 0.872340 (-6350 4725);
DISPLAY INVISIBLE (-6350 4725);
FORCEPROP 1 LAST PATH I269
J 2
(-6023 4850);
DISPLAY 0.872340 (-6023 4850);
PAINT GREEN (-6023 4850);
DISPLAY INVISIBLE (-6023 4850);
FORCEADD TAP..1
R 2
(-6025 4750);
FORCEPROP 3 LASTPIN (-5975 4750) SIG_NAME M_E_CPU0_SB_DQS_DN<2>
J 0
(-5965 4760);
DISPLAY 0.659574 (-5965 4760);
PAINT MONO (-5965 4760);
DISPLAY INVISIBLE (-5965 4760);
FORCEPROP 1 LASTPIN (-5975 4750) BN 2
J 2
(-5963 4758);
DISPLAY 0.489362 (-5963 4758);
PAINT GREEN (-5963 4758);
FORCEPROP 2 LAST CDS_LIB mstr_standard
J 2
(-6025 4750);
DISPLAY 0.723404 (-6025 4750);
PAINT MONO (-6025 4750);
DISPLAY INVISIBLE (-6025 4750);
FORCEPROP 1 LAST BODY_TYPE PLUMBING
J 2
(-6025 4800);
DISPLAY 0.872340 (-6025 4800);
PAINT GREEN (-6025 4800);
DISPLAY INVISIBLE (-6025 4800);
FORCEPROP 1 LAST HDL_TAP TRUE
J 2
(-6350 4625);
DISPLAY 0.872340 (-6350 4625);
DISPLAY INVISIBLE (-6350 4625);
FORCEPROP 1 LAST PATH I270
J 2
(-6023 4750);
DISPLAY 0.872340 (-6023 4750);
PAINT GREEN (-6023 4750);
DISPLAY INVISIBLE (-6023 4750);
FORCEADD TAP..1
R 2
(-6025 4650);
FORCEPROP 3 LASTPIN (-5975 4650) SIG_NAME M_E_CPU0_SB_DQS_DN<3>
J 0
(-5965 4660);
DISPLAY 0.659574 (-5965 4660);
PAINT MONO (-5965 4660);
DISPLAY INVISIBLE (-5965 4660);
FORCEPROP 1 LASTPIN (-5975 4650) BN 3
J 2
(-5963 4658);
DISPLAY 0.489362 (-5963 4658);
PAINT GREEN (-5963 4658);
FORCEPROP 2 LAST CDS_LIB mstr_standard
J 2
(-6025 4650);
DISPLAY 0.723404 (-6025 4650);
PAINT MONO (-6025 4650);
DISPLAY INVISIBLE (-6025 4650);
FORCEPROP 1 LAST BODY_TYPE PLUMBING
J 2
(-6025 4700);
DISPLAY 0.872340 (-6025 4700);
PAINT GREEN (-6025 4700);
DISPLAY INVISIBLE (-6025 4700);
FORCEPROP 1 LAST HDL_TAP TRUE
J 2
(-6350 4525);
DISPLAY 0.872340 (-6350 4525);
DISPLAY INVISIBLE (-6350 4525);
FORCEPROP 1 LAST PATH I271
J 2
(-6023 4650);
DISPLAY 0.872340 (-6023 4650);
PAINT GREEN (-6023 4650);
DISPLAY INVISIBLE (-6023 4650);
FORCEADD TAP..1
R 2
(-5825 4600);
FORCEPROP 3 LASTPIN (-5775 4600) SIG_NAME M_E_CPU0_SB_DQS_DP<4>
J 0
(-5765 4610);
DISPLAY 0.659574 (-5765 4610);
PAINT MONO (-5765 4610);
DISPLAY INVISIBLE (-5765 4610);
FORCEPROP 1 LASTPIN (-5775 4600) BN 4
J 2
(-5763 4608);
DISPLAY 0.489362 (-5763 4608);
PAINT GREEN (-5763 4608);
FORCEPROP 2 LAST CDS_LIB mstr_standard
J 2
(-5825 4600);
DISPLAY 0.723404 (-5825 4600);
PAINT MONO (-5825 4600);
DISPLAY INVISIBLE (-5825 4600);
FORCEPROP 1 LAST BODY_TYPE PLUMBING
J 2
(-5825 4650);
DISPLAY 0.872340 (-5825 4650);
PAINT GREEN (-5825 4650);
DISPLAY INVISIBLE (-5825 4650);
FORCEPROP 1 LAST HDL_TAP TRUE
J 2
(-6150 4475);
DISPLAY 0.872340 (-6150 4475);
DISPLAY INVISIBLE (-6150 4475);
FORCEPROP 1 LAST PATH I272
J 2
(-5823 4600);
DISPLAY 0.872340 (-5823 4600);
PAINT GREEN (-5823 4600);
DISPLAY INVISIBLE (-5823 4600);
FORCEADD TAP..1
R 2
(-5825 4500);
FORCEPROP 3 LASTPIN (-5775 4500) SIG_NAME M_E_CPU0_SB_DQS_DP<5>
J 0
(-5765 4510);
DISPLAY 0.659574 (-5765 4510);
PAINT MONO (-5765 4510);
DISPLAY INVISIBLE (-5765 4510);
FORCEPROP 1 LASTPIN (-5775 4500) BN 5
J 2
(-5763 4508);
DISPLAY 0.489362 (-5763 4508);
PAINT GREEN (-5763 4508);
FORCEPROP 2 LAST CDS_LIB mstr_standard
J 2
(-5825 4500);
DISPLAY 0.723404 (-5825 4500);
PAINT MONO (-5825 4500);
DISPLAY INVISIBLE (-5825 4500);
FORCEPROP 1 LAST BODY_TYPE PLUMBING
J 2
(-5825 4550);
DISPLAY 0.872340 (-5825 4550);
PAINT GREEN (-5825 4550);
DISPLAY INVISIBLE (-5825 4550);
FORCEPROP 1 LAST HDL_TAP TRUE
J 2
(-6150 4375);
DISPLAY 0.872340 (-6150 4375);
DISPLAY INVISIBLE (-6150 4375);
FORCEPROP 1 LAST PATH I273
J 2
(-5823 4500);
DISPLAY 0.872340 (-5823 4500);
PAINT GREEN (-5823 4500);
DISPLAY INVISIBLE (-5823 4500);
FORCEADD TAP..1
R 2
(-5825 4400);
FORCEPROP 3 LASTPIN (-5775 4400) SIG_NAME M_E_CPU0_SB_DQS_DP<6>
J 0
(-5765 4410);
DISPLAY 0.659574 (-5765 4410);
PAINT MONO (-5765 4410);
DISPLAY INVISIBLE (-5765 4410);
FORCEPROP 1 LASTPIN (-5775 4400) BN 6
J 2
(-5763 4408);
DISPLAY 0.489362 (-5763 4408);
PAINT GREEN (-5763 4408);
FORCEPROP 2 LAST CDS_LIB mstr_standard
J 2
(-5825 4400);
DISPLAY 0.723404 (-5825 4400);
PAINT MONO (-5825 4400);
DISPLAY INVISIBLE (-5825 4400);
FORCEPROP 1 LAST BODY_TYPE PLUMBING
J 2
(-5825 4450);
DISPLAY 0.872340 (-5825 4450);
PAINT GREEN (-5825 4450);
DISPLAY INVISIBLE (-5825 4450);
FORCEPROP 1 LAST HDL_TAP TRUE
J 2
(-6150 4275);
DISPLAY 0.872340 (-6150 4275);
DISPLAY INVISIBLE (-6150 4275);
FORCEPROP 1 LAST PATH I274
J 2
(-5823 4400);
DISPLAY 0.872340 (-5823 4400);
PAINT GREEN (-5823 4400);
DISPLAY INVISIBLE (-5823 4400);
FORCEADD TAP..1
R 2
(-5825 4200);
FORCEPROP 3 LASTPIN (-5775 4200) SIG_NAME M_E_CPU0_SB_DQS_DP<8>
J 0
(-5765 4210);
DISPLAY 0.659574 (-5765 4210);
PAINT MONO (-5765 4210);
DISPLAY INVISIBLE (-5765 4210);
FORCEPROP 1 LASTPIN (-5775 4200) BN 8
J 2
(-5763 4208);
DISPLAY 0.489362 (-5763 4208);
PAINT GREEN (-5763 4208);
FORCEPROP 2 LAST CDS_LIB mstr_standard
J 2
(-5825 4200);
DISPLAY 0.723404 (-5825 4200);
PAINT MONO (-5825 4200);
DISPLAY INVISIBLE (-5825 4200);
FORCEPROP 1 LAST BODY_TYPE PLUMBING
J 2
(-5825 4250);
DISPLAY 0.872340 (-5825 4250);
PAINT GREEN (-5825 4250);
DISPLAY INVISIBLE (-5825 4250);
FORCEPROP 1 LAST HDL_TAP TRUE
J 2
(-6150 4075);
DISPLAY 0.872340 (-6150 4075);
DISPLAY INVISIBLE (-6150 4075);
FORCEPROP 1 LAST PATH I275
J 2
(-5823 4200);
DISPLAY 0.872340 (-5823 4200);
PAINT GREEN (-5823 4200);
DISPLAY INVISIBLE (-5823 4200);
FORCEADD TAP..1
R 2
(-5825 4300);
FORCEPROP 3 LASTPIN (-5775 4300) SIG_NAME M_E_CPU0_SB_DQS_DP<7>
J 0
(-5765 4310);
DISPLAY 0.659574 (-5765 4310);
PAINT MONO (-5765 4310);
DISPLAY INVISIBLE (-5765 4310);
FORCEPROP 1 LASTPIN (-5775 4300) BN 7
J 2
(-5763 4308);
DISPLAY 0.489362 (-5763 4308);
PAINT GREEN (-5763 4308);
FORCEPROP 2 LAST CDS_LIB mstr_standard
J 2
(-5825 4300);
DISPLAY 0.723404 (-5825 4300);
PAINT MONO (-5825 4300);
DISPLAY INVISIBLE (-5825 4300);
FORCEPROP 1 LAST BODY_TYPE PLUMBING
J 2
(-5825 4350);
DISPLAY 0.872340 (-5825 4350);
PAINT GREEN (-5825 4350);
DISPLAY INVISIBLE (-5825 4350);
FORCEPROP 1 LAST HDL_TAP TRUE
J 2
(-6150 4175);
DISPLAY 0.872340 (-6150 4175);
DISPLAY INVISIBLE (-6150 4175);
FORCEPROP 1 LAST PATH I276
J 2
(-5823 4300);
DISPLAY 0.872340 (-5823 4300);
PAINT GREEN (-5823 4300);
DISPLAY INVISIBLE (-5823 4300);
FORCEADD TAP..1
R 2
(-5825 4100);
FORCEPROP 3 LASTPIN (-5775 4100) SIG_NAME M_E_CPU0_SB_DQS_DP<9>
J 0
(-5765 4110);
DISPLAY 0.659574 (-5765 4110);
PAINT MONO (-5765 4110);
DISPLAY INVISIBLE (-5765 4110);
FORCEPROP 1 LASTPIN (-5775 4100) BN 9
J 2
(-5763 4108);
DISPLAY 0.489362 (-5763 4108);
PAINT GREEN (-5763 4108);
FORCEPROP 2 LAST CDS_LIB mstr_standard
J 2
(-5825 4100);
DISPLAY 0.723404 (-5825 4100);
PAINT MONO (-5825 4100);
DISPLAY INVISIBLE (-5825 4100);
FORCEPROP 1 LAST BODY_TYPE PLUMBING
J 2
(-5825 4150);
DISPLAY 0.872340 (-5825 4150);
PAINT GREEN (-5825 4150);
DISPLAY INVISIBLE (-5825 4150);
FORCEPROP 1 LAST HDL_TAP TRUE
J 2
(-6150 3975);
DISPLAY 0.872340 (-6150 3975);
DISPLAY INVISIBLE (-6150 3975);
FORCEPROP 1 LAST PATH I277
J 2
(-5823 4100);
DISPLAY 0.872340 (-5823 4100);
PAINT GREEN (-5823 4100);
DISPLAY INVISIBLE (-5823 4100);
FORCEADD TAP..1
R 2
(-6025 4550);
FORCEPROP 3 LASTPIN (-5975 4550) SIG_NAME M_E_CPU0_SB_DQS_DN<4>
J 0
(-5965 4560);
DISPLAY 0.659574 (-5965 4560);
PAINT MONO (-5965 4560);
DISPLAY INVISIBLE (-5965 4560);
FORCEPROP 1 LASTPIN (-5975 4550) BN 4
J 2
(-5963 4558);
DISPLAY 0.489362 (-5963 4558);
PAINT GREEN (-5963 4558);
FORCEPROP 2 LAST CDS_LIB mstr_standard
J 2
(-6025 4550);
DISPLAY 0.723404 (-6025 4550);
PAINT MONO (-6025 4550);
DISPLAY INVISIBLE (-6025 4550);
FORCEPROP 1 LAST BODY_TYPE PLUMBING
J 2
(-6025 4600);
DISPLAY 0.872340 (-6025 4600);
PAINT GREEN (-6025 4600);
DISPLAY INVISIBLE (-6025 4600);
FORCEPROP 1 LAST HDL_TAP TRUE
J 2
(-6350 4425);
DISPLAY 0.872340 (-6350 4425);
DISPLAY INVISIBLE (-6350 4425);
FORCEPROP 1 LAST PATH I278
J 2
(-6023 4550);
DISPLAY 0.872340 (-6023 4550);
PAINT GREEN (-6023 4550);
DISPLAY INVISIBLE (-6023 4550);
FORCEADD TAP..1
R 2
(-6025 4450);
FORCEPROP 3 LASTPIN (-5975 4450) SIG_NAME M_E_CPU0_SB_DQS_DN<5>
J 0
(-5965 4460);
DISPLAY 0.659574 (-5965 4460);
PAINT MONO (-5965 4460);
DISPLAY INVISIBLE (-5965 4460);
FORCEPROP 1 LASTPIN (-5975 4450) BN 5
J 2
(-5963 4458);
DISPLAY 0.489362 (-5963 4458);
PAINT GREEN (-5963 4458);
FORCEPROP 2 LAST CDS_LIB mstr_standard
J 2
(-6025 4450);
DISPLAY 0.723404 (-6025 4450);
PAINT MONO (-6025 4450);
DISPLAY INVISIBLE (-6025 4450);
FORCEPROP 1 LAST BODY_TYPE PLUMBING
J 2
(-6025 4500);
DISPLAY 0.872340 (-6025 4500);
PAINT GREEN (-6025 4500);
DISPLAY INVISIBLE (-6025 4500);
FORCEPROP 1 LAST HDL_TAP TRUE
J 2
(-6350 4325);
DISPLAY 0.872340 (-6350 4325);
DISPLAY INVISIBLE (-6350 4325);
FORCEPROP 1 LAST PATH I279
J 2
(-6023 4450);
DISPLAY 0.872340 (-6023 4450);
PAINT GREEN (-6023 4450);
DISPLAY INVISIBLE (-6023 4450);
FORCEADD TAP..1
R 2
(-6025 4350);
FORCEPROP 3 LASTPIN (-5975 4350) SIG_NAME M_E_CPU0_SB_DQS_DN<6>
J 0
(-5965 4360);
DISPLAY 0.659574 (-5965 4360);
PAINT MONO (-5965 4360);
DISPLAY INVISIBLE (-5965 4360);
FORCEPROP 1 LASTPIN (-5975 4350) BN 6
J 2
(-5963 4358);
DISPLAY 0.489362 (-5963 4358);
PAINT GREEN (-5963 4358);
FORCEPROP 2 LAST CDS_LIB mstr_standard
J 2
(-6025 4350);
DISPLAY 0.723404 (-6025 4350);
PAINT MONO (-6025 4350);
DISPLAY INVISIBLE (-6025 4350);
FORCEPROP 1 LAST BODY_TYPE PLUMBING
J 2
(-6025 4400);
DISPLAY 0.872340 (-6025 4400);
PAINT GREEN (-6025 4400);
DISPLAY INVISIBLE (-6025 4400);
FORCEPROP 1 LAST HDL_TAP TRUE
J 2
(-6350 4225);
DISPLAY 0.872340 (-6350 4225);
DISPLAY INVISIBLE (-6350 4225);
FORCEPROP 1 LAST PATH I280
J 2
(-6023 4350);
DISPLAY 0.872340 (-6023 4350);
PAINT GREEN (-6023 4350);
DISPLAY INVISIBLE (-6023 4350);
FORCEADD TAP..1
R 2
(-6025 4250);
FORCEPROP 3 LASTPIN (-5975 4250) SIG_NAME M_E_CPU0_SB_DQS_DN<7>
J 0
(-5965 4260);
DISPLAY 0.659574 (-5965 4260);
PAINT MONO (-5965 4260);
DISPLAY INVISIBLE (-5965 4260);
FORCEPROP 1 LASTPIN (-5975 4250) BN 7
J 2
(-5963 4258);
DISPLAY 0.489362 (-5963 4258);
PAINT GREEN (-5963 4258);
FORCEPROP 2 LAST CDS_LIB mstr_standard
J 2
(-6025 4250);
DISPLAY 0.723404 (-6025 4250);
PAINT MONO (-6025 4250);
DISPLAY INVISIBLE (-6025 4250);
FORCEPROP 1 LAST BODY_TYPE PLUMBING
J 2
(-6025 4300);
DISPLAY 0.872340 (-6025 4300);
PAINT GREEN (-6025 4300);
DISPLAY INVISIBLE (-6025 4300);
FORCEPROP 1 LAST HDL_TAP TRUE
J 2
(-6350 4125);
DISPLAY 0.872340 (-6350 4125);
DISPLAY INVISIBLE (-6350 4125);
FORCEPROP 1 LAST PATH I281
J 2
(-6023 4250);
DISPLAY 0.872340 (-6023 4250);
PAINT GREEN (-6023 4250);
DISPLAY INVISIBLE (-6023 4250);
FORCEADD TAP..1
R 2
(-6025 4150);
FORCEPROP 3 LASTPIN (-5975 4150) SIG_NAME M_E_CPU0_SB_DQS_DN<8>
J 0
(-5965 4160);
DISPLAY 0.659574 (-5965 4160);
PAINT MONO (-5965 4160);
DISPLAY INVISIBLE (-5965 4160);
FORCEPROP 1 LASTPIN (-5975 4150) BN 8
J 2
(-5963 4158);
DISPLAY 0.489362 (-5963 4158);
PAINT GREEN (-5963 4158);
FORCEPROP 2 LAST CDS_LIB mstr_standard
J 2
(-6025 4150);
DISPLAY 0.723404 (-6025 4150);
PAINT MONO (-6025 4150);
DISPLAY INVISIBLE (-6025 4150);
FORCEPROP 1 LAST BODY_TYPE PLUMBING
J 2
(-6025 4200);
DISPLAY 0.872340 (-6025 4200);
PAINT GREEN (-6025 4200);
DISPLAY INVISIBLE (-6025 4200);
FORCEPROP 1 LAST HDL_TAP TRUE
J 2
(-6350 4025);
DISPLAY 0.872340 (-6350 4025);
DISPLAY INVISIBLE (-6350 4025);
FORCEPROP 1 LAST PATH I282
J 2
(-6023 4150);
DISPLAY 0.872340 (-6023 4150);
PAINT GREEN (-6023 4150);
DISPLAY INVISIBLE (-6023 4150);
FORCEADD OFFPAGE..3
R 2
(-6725 6075);
FORCEPROP 2 LAST $XR0 89 
J 0
(-6974 6075);
DISPLAY 0.638298 (-6974 6075);
PAINT MONO (-6974 6075);
FORCEPROP 2 LAST PATH I283
J 0
(-7000 6125);
DISPLAY 1.021277 (-7000 6125);
DISPLAY INVISIBLE (-7000 6125);
FORCEPROP 1 LAST COMMENT_BODY TRUE
J 2
(-6675 5975);
DISPLAY 0.872340 (-6675 5975);
PAINT GREEN (-6675 5975);
DISPLAY INVISIBLE (-6675 5975);
FORCEPROP 1 LAST OFFPAGE TRUE
J 2
(-7050 5950);
DISPLAY 0.872340 (-7050 5950);
PAINT GREEN (-7050 5950);
DISPLAY INVISIBLE (-7050 5950);
FORCEPROP 2 LAST CDS_LIB standard
J 0
(-6725 6075);
DISPLAY INVISIBLE (-6725 6075);
FORCEADD OFFPAGE..3
R 2
(-6725 6025);
FORCEPROP 2 LAST $XR0 89 
J 0
(-6974 6025);
DISPLAY 0.638298 (-6974 6025);
PAINT MONO (-6974 6025);
FORCEPROP 2 LAST PATH I284
J 0
(-7000 6075);
DISPLAY 1.021277 (-7000 6075);
DISPLAY INVISIBLE (-7000 6075);
FORCEPROP 1 LAST COMMENT_BODY TRUE
J 2
(-6675 5925);
DISPLAY 0.872340 (-6675 5925);
PAINT GREEN (-6675 5925);
DISPLAY INVISIBLE (-6675 5925);
FORCEPROP 1 LAST OFFPAGE TRUE
J 2
(-7050 5900);
DISPLAY 0.872340 (-7050 5900);
PAINT GREEN (-7050 5900);
DISPLAY INVISIBLE (-7050 5900);
FORCEPROP 2 LAST CDS_LIB standard
J 0
(-6725 6025);
DISPLAY INVISIBLE (-6725 6025);
FORCEADD OFFPAGE..3
R 2
(-6725 5025);
FORCEPROP 2 LAST $XR0 89 
J 0
(-6974 5025);
DISPLAY 0.638298 (-6974 5025);
PAINT MONO (-6974 5025);
FORCEPROP 2 LAST PATH I285
J 0
(-7000 5075);
DISPLAY 1.021277 (-7000 5075);
DISPLAY INVISIBLE (-7000 5075);
FORCEPROP 1 LAST COMMENT_BODY TRUE
J 2
(-6675 4925);
DISPLAY 0.872340 (-6675 4925);
PAINT GREEN (-6675 4925);
DISPLAY INVISIBLE (-6675 4925);
FORCEPROP 1 LAST OFFPAGE TRUE
J 2
(-7050 4900);
DISPLAY 0.872340 (-7050 4900);
PAINT GREEN (-7050 4900);
DISPLAY INVISIBLE (-7050 4900);
FORCEPROP 2 LAST CDS_LIB standard
J 0
(-6725 5025);
DISPLAY INVISIBLE (-6725 5025);
FORCEADD OFFPAGE..3
R 2
(-6725 4975);
FORCEPROP 2 LAST $XR0 89 
J 0
(-6974 4975);
DISPLAY 0.638298 (-6974 4975);
PAINT MONO (-6974 4975);
FORCEPROP 2 LAST PATH I286
J 0
(-7000 5025);
DISPLAY 1.021277 (-7000 5025);
DISPLAY INVISIBLE (-7000 5025);
FORCEPROP 1 LAST COMMENT_BODY TRUE
J 2
(-6675 4875);
DISPLAY 0.872340 (-6675 4875);
PAINT GREEN (-6675 4875);
DISPLAY INVISIBLE (-6675 4875);
FORCEPROP 1 LAST OFFPAGE TRUE
J 2
(-7050 4850);
DISPLAY 0.872340 (-7050 4850);
PAINT GREEN (-7050 4850);
DISPLAY INVISIBLE (-7050 4850);
FORCEPROP 2 LAST CDS_LIB standard
J 0
(-6725 4975);
DISPLAY INVISIBLE (-6725 4975);
FORCEADD TAP..1
R 2
(-6025 4050);
FORCEPROP 3 LASTPIN (-5975 4050) SIG_NAME M_E_CPU0_SB_DQS_DN<9>
J 0
(-5965 4060);
DISPLAY 0.659574 (-5965 4060);
PAINT MONO (-5965 4060);
DISPLAY INVISIBLE (-5965 4060);
FORCEPROP 1 LASTPIN (-5975 4050) BN 9
J 2
(-5963 4058);
DISPLAY 0.489362 (-5963 4058);
PAINT GREEN (-5963 4058);
FORCEPROP 2 LAST CDS_LIB mstr_standard
J 2
(-6025 4050);
DISPLAY 0.723404 (-6025 4050);
PAINT MONO (-6025 4050);
DISPLAY INVISIBLE (-6025 4050);
FORCEPROP 1 LAST BODY_TYPE PLUMBING
J 2
(-6025 4100);
DISPLAY 0.872340 (-6025 4100);
PAINT GREEN (-6025 4100);
DISPLAY INVISIBLE (-6025 4100);
FORCEPROP 1 LAST HDL_TAP TRUE
J 2
(-6350 3925);
DISPLAY 0.872340 (-6350 3925);
DISPLAY INVISIBLE (-6350 3925);
FORCEPROP 1 LAST PATH I287
J 2
(-6023 4050);
DISPLAY 0.872340 (-6023 4050);
PAINT GREEN (-6023 4050);
DISPLAY INVISIBLE (-6023 4050);
FORCEADD TAP..1
R 2
(-6025 3900);
FORCEPROP 3 LASTPIN (-5975 3900) SIG_NAME M_E_CPU0_SA_CA<0>
J 0
(-5965 3910);
DISPLAY 0.659574 (-5965 3910);
PAINT MONO (-5965 3910);
DISPLAY INVISIBLE (-5965 3910);
FORCEPROP 1 LASTPIN (-5975 3900) BN 0
J 2
(-5963 3908);
DISPLAY 0.489362 (-5963 3908);
PAINT GREEN (-5963 3908);
FORCEPROP 2 LAST CDS_LIB mstr_standard
J 0
(-6025 3900);
DISPLAY 0.723404 (-6025 3900);
PAINT MONO (-6025 3900);
DISPLAY INVISIBLE (-6025 3900);
FORCEPROP 1 LAST BODY_TYPE PLUMBING
J 2
(-6025 3950);
DISPLAY 0.872340 (-6025 3950);
PAINT GREEN (-6025 3950);
DISPLAY INVISIBLE (-6025 3950);
FORCEPROP 1 LAST HDL_TAP TRUE
J 2
(-6350 3775);
DISPLAY 0.872340 (-6350 3775);
DISPLAY INVISIBLE (-6350 3775);
FORCEPROP 1 LAST PATH I288
J 2
(-6023 3900);
DISPLAY 0.872340 (-6023 3900);
PAINT GREEN (-6023 3900);
DISPLAY INVISIBLE (-6023 3900);
FORCEADD TAP..1
R 2
(-6025 3850);
FORCEPROP 3 LASTPIN (-5975 3850) SIG_NAME M_E_CPU0_SA_CA<1>
J 0
(-5965 3860);
DISPLAY 0.659574 (-5965 3860);
PAINT MONO (-5965 3860);
DISPLAY INVISIBLE (-5965 3860);
FORCEPROP 1 LASTPIN (-5975 3850) BN 1
J 2
(-5963 3858);
DISPLAY 0.489362 (-5963 3858);
PAINT GREEN (-5963 3858);
FORCEPROP 2 LAST CDS_LIB mstr_standard
J 0
(-6025 3850);
DISPLAY 0.723404 (-6025 3850);
PAINT MONO (-6025 3850);
DISPLAY INVISIBLE (-6025 3850);
FORCEPROP 1 LAST BODY_TYPE PLUMBING
J 2
(-6025 3900);
DISPLAY 0.872340 (-6025 3900);
PAINT GREEN (-6025 3900);
DISPLAY INVISIBLE (-6025 3900);
FORCEPROP 1 LAST HDL_TAP TRUE
J 2
(-6350 3725);
DISPLAY 0.872340 (-6350 3725);
DISPLAY INVISIBLE (-6350 3725);
FORCEPROP 1 LAST PATH I289
J 2
(-6023 3850);
DISPLAY 0.872340 (-6023 3850);
PAINT GREEN (-6023 3850);
DISPLAY INVISIBLE (-6023 3850);
FORCEADD TAP..1
R 2
(-6025 3800);
FORCEPROP 3 LASTPIN (-5975 3800) SIG_NAME M_E_CPU0_SA_CA<2>
J 0
(-5965 3810);
DISPLAY 0.659574 (-5965 3810);
PAINT MONO (-5965 3810);
DISPLAY INVISIBLE (-5965 3810);
FORCEPROP 1 LASTPIN (-5975 3800) BN 2
J 2
(-5963 3808);
DISPLAY 0.489362 (-5963 3808);
PAINT GREEN (-5963 3808);
FORCEPROP 2 LAST CDS_LIB mstr_standard
J 0
(-6025 3800);
DISPLAY 0.723404 (-6025 3800);
PAINT MONO (-6025 3800);
DISPLAY INVISIBLE (-6025 3800);
FORCEPROP 1 LAST BODY_TYPE PLUMBING
J 2
(-6025 3850);
DISPLAY 0.872340 (-6025 3850);
PAINT GREEN (-6025 3850);
DISPLAY INVISIBLE (-6025 3850);
FORCEPROP 1 LAST HDL_TAP TRUE
J 2
(-6350 3675);
DISPLAY 0.872340 (-6350 3675);
DISPLAY INVISIBLE (-6350 3675);
FORCEPROP 1 LAST PATH I290
J 2
(-6023 3800);
DISPLAY 0.872340 (-6023 3800);
PAINT GREEN (-6023 3800);
DISPLAY INVISIBLE (-6023 3800);
FORCEADD TAP..1
R 2
(-6025 3750);
FORCEPROP 3 LASTPIN (-5975 3750) SIG_NAME M_E_CPU0_SA_CA<3>
J 0
(-5965 3760);
DISPLAY 0.659574 (-5965 3760);
PAINT MONO (-5965 3760);
DISPLAY INVISIBLE (-5965 3760);
FORCEPROP 1 LASTPIN (-5975 3750) BN 3
J 2
(-5963 3758);
DISPLAY 0.489362 (-5963 3758);
PAINT GREEN (-5963 3758);
FORCEPROP 2 LAST CDS_LIB mstr_standard
J 0
(-6025 3750);
DISPLAY 0.723404 (-6025 3750);
PAINT MONO (-6025 3750);
DISPLAY INVISIBLE (-6025 3750);
FORCEPROP 1 LAST BODY_TYPE PLUMBING
J 2
(-6025 3800);
DISPLAY 0.872340 (-6025 3800);
PAINT GREEN (-6025 3800);
DISPLAY INVISIBLE (-6025 3800);
FORCEPROP 1 LAST HDL_TAP TRUE
J 2
(-6350 3625);
DISPLAY 0.872340 (-6350 3625);
DISPLAY INVISIBLE (-6350 3625);
FORCEPROP 1 LAST PATH I291
J 2
(-6023 3750);
DISPLAY 0.872340 (-6023 3750);
PAINT GREEN (-6023 3750);
DISPLAY INVISIBLE (-6023 3750);
FORCEADD TAP..1
R 2
(-6025 3600);
FORCEPROP 3 LASTPIN (-5975 3600) SIG_NAME M_E_CPU0_SA_CA<6>
J 0
(-5965 3610);
DISPLAY 0.659574 (-5965 3610);
PAINT MONO (-5965 3610);
DISPLAY INVISIBLE (-5965 3610);
FORCEPROP 1 LASTPIN (-5975 3600) BN 6
J 2
(-5963 3608);
DISPLAY 0.489362 (-5963 3608);
PAINT GREEN (-5963 3608);
FORCEPROP 2 LAST CDS_LIB mstr_standard
J 0
(-6025 3600);
DISPLAY 0.723404 (-6025 3600);
PAINT MONO (-6025 3600);
DISPLAY INVISIBLE (-6025 3600);
FORCEPROP 1 LAST BODY_TYPE PLUMBING
J 2
(-6025 3650);
DISPLAY 0.872340 (-6025 3650);
PAINT GREEN (-6025 3650);
DISPLAY INVISIBLE (-6025 3650);
FORCEPROP 1 LAST HDL_TAP TRUE
J 2
(-6350 3475);
DISPLAY 0.872340 (-6350 3475);
DISPLAY INVISIBLE (-6350 3475);
FORCEPROP 1 LAST PATH I292
J 2
(-6023 3600);
DISPLAY 0.872340 (-6023 3600);
PAINT GREEN (-6023 3600);
DISPLAY INVISIBLE (-6023 3600);
FORCEADD TAP..1
R 2
(-6025 3650);
FORCEPROP 3 LASTPIN (-5975 3650) SIG_NAME M_E_CPU0_SA_CA<5>
J 0
(-5965 3660);
DISPLAY 0.659574 (-5965 3660);
PAINT MONO (-5965 3660);
DISPLAY INVISIBLE (-5965 3660);
FORCEPROP 1 LASTPIN (-5975 3650) BN 5
J 2
(-5963 3658);
DISPLAY 0.489362 (-5963 3658);
PAINT GREEN (-5963 3658);
FORCEPROP 2 LAST CDS_LIB mstr_standard
J 0
(-6025 3650);
DISPLAY 0.723404 (-6025 3650);
PAINT MONO (-6025 3650);
DISPLAY INVISIBLE (-6025 3650);
FORCEPROP 1 LAST BODY_TYPE PLUMBING
J 2
(-6025 3700);
DISPLAY 0.872340 (-6025 3700);
PAINT GREEN (-6025 3700);
DISPLAY INVISIBLE (-6025 3700);
FORCEPROP 1 LAST HDL_TAP TRUE
J 2
(-6350 3525);
DISPLAY 0.872340 (-6350 3525);
DISPLAY INVISIBLE (-6350 3525);
FORCEPROP 1 LAST PATH I293
J 2
(-6023 3650);
DISPLAY 0.872340 (-6023 3650);
PAINT GREEN (-6023 3650);
DISPLAY INVISIBLE (-6023 3650);
FORCEADD TAP..1
R 2
(-6025 3700);
FORCEPROP 3 LASTPIN (-5975 3700) SIG_NAME M_E_CPU0_SA_CA<4>
J 0
(-5965 3710);
DISPLAY 0.659574 (-5965 3710);
PAINT MONO (-5965 3710);
DISPLAY INVISIBLE (-5965 3710);
FORCEPROP 1 LASTPIN (-5975 3700) BN 4
J 2
(-5963 3708);
DISPLAY 0.489362 (-5963 3708);
PAINT GREEN (-5963 3708);
FORCEPROP 2 LAST CDS_LIB mstr_standard
J 0
(-6025 3700);
DISPLAY 0.723404 (-6025 3700);
PAINT MONO (-6025 3700);
DISPLAY INVISIBLE (-6025 3700);
FORCEPROP 1 LAST BODY_TYPE PLUMBING
J 2
(-6025 3750);
DISPLAY 0.872340 (-6025 3750);
PAINT GREEN (-6025 3750);
DISPLAY INVISIBLE (-6025 3750);
FORCEPROP 1 LAST HDL_TAP TRUE
J 2
(-6350 3575);
DISPLAY 0.872340 (-6350 3575);
DISPLAY INVISIBLE (-6350 3575);
FORCEPROP 1 LAST PATH I294
J 2
(-6023 3700);
DISPLAY 0.872340 (-6023 3700);
PAINT GREEN (-6023 3700);
DISPLAY INVISIBLE (-6023 3700);
FORCEADD TAP..1
R 2
(-6025 3500);
FORCEPROP 3 LASTPIN (-5975 3500) SIG_NAME M_E_CPU0_SB_CA<0>
J 0
(-5965 3510);
DISPLAY 0.659574 (-5965 3510);
PAINT MONO (-5965 3510);
DISPLAY INVISIBLE (-5965 3510);
FORCEPROP 1 LASTPIN (-5975 3500) BN 0
J 2
(-5963 3508);
DISPLAY 0.489362 (-5963 3508);
PAINT GREEN (-5963 3508);
FORCEPROP 2 LAST CDS_LIB mstr_standard
J 0
(-6025 3500);
DISPLAY 0.723404 (-6025 3500);
PAINT MONO (-6025 3500);
DISPLAY INVISIBLE (-6025 3500);
FORCEPROP 1 LAST BODY_TYPE PLUMBING
J 2
(-6025 3550);
DISPLAY 0.872340 (-6025 3550);
PAINT GREEN (-6025 3550);
DISPLAY INVISIBLE (-6025 3550);
FORCEPROP 1 LAST HDL_TAP TRUE
J 2
(-6350 3375);
DISPLAY 0.872340 (-6350 3375);
DISPLAY INVISIBLE (-6350 3375);
FORCEPROP 1 LAST PATH I295
J 2
(-6023 3500);
DISPLAY 0.872340 (-6023 3500);
PAINT GREEN (-6023 3500);
DISPLAY INVISIBLE (-6023 3500);
FORCEADD TAP..1
R 2
(-6025 3450);
FORCEPROP 3 LASTPIN (-5975 3450) SIG_NAME M_E_CPU0_SB_CA<1>
J 0
(-5965 3460);
DISPLAY 0.659574 (-5965 3460);
PAINT MONO (-5965 3460);
DISPLAY INVISIBLE (-5965 3460);
FORCEPROP 1 LASTPIN (-5975 3450) BN 1
J 2
(-5963 3458);
DISPLAY 0.489362 (-5963 3458);
PAINT GREEN (-5963 3458);
FORCEPROP 2 LAST CDS_LIB mstr_standard
J 0
(-6025 3450);
DISPLAY 0.723404 (-6025 3450);
PAINT MONO (-6025 3450);
DISPLAY INVISIBLE (-6025 3450);
FORCEPROP 1 LAST BODY_TYPE PLUMBING
J 2
(-6025 3500);
DISPLAY 0.872340 (-6025 3500);
PAINT GREEN (-6025 3500);
DISPLAY INVISIBLE (-6025 3500);
FORCEPROP 1 LAST HDL_TAP TRUE
J 2
(-6350 3325);
DISPLAY 0.872340 (-6350 3325);
DISPLAY INVISIBLE (-6350 3325);
FORCEPROP 1 LAST PATH I296
J 2
(-6023 3450);
DISPLAY 0.872340 (-6023 3450);
PAINT GREEN (-6023 3450);
DISPLAY INVISIBLE (-6023 3450);
FORCEADD TAP..1
R 2
(-6025 3350);
FORCEPROP 3 LASTPIN (-5975 3350) SIG_NAME M_E_CPU0_SB_CA<3>
J 0
(-5965 3360);
DISPLAY 0.659574 (-5965 3360);
PAINT MONO (-5965 3360);
DISPLAY INVISIBLE (-5965 3360);
FORCEPROP 1 LASTPIN (-5975 3350) BN 3
J 2
(-5963 3358);
DISPLAY 0.489362 (-5963 3358);
PAINT GREEN (-5963 3358);
FORCEPROP 2 LAST CDS_LIB mstr_standard
J 0
(-6025 3350);
DISPLAY 0.723404 (-6025 3350);
PAINT MONO (-6025 3350);
DISPLAY INVISIBLE (-6025 3350);
FORCEPROP 1 LAST BODY_TYPE PLUMBING
J 2
(-6025 3400);
DISPLAY 0.872340 (-6025 3400);
PAINT GREEN (-6025 3400);
DISPLAY INVISIBLE (-6025 3400);
FORCEPROP 1 LAST HDL_TAP TRUE
J 2
(-6350 3225);
DISPLAY 0.872340 (-6350 3225);
DISPLAY INVISIBLE (-6350 3225);
FORCEPROP 1 LAST PATH I297
J 2
(-6023 3350);
DISPLAY 0.872340 (-6023 3350);
PAINT GREEN (-6023 3350);
DISPLAY INVISIBLE (-6023 3350);
FORCEADD TAP..1
R 2
(-6025 3400);
FORCEPROP 3 LASTPIN (-5975 3400) SIG_NAME M_E_CPU0_SB_CA<2>
J 0
(-5965 3410);
DISPLAY 0.659574 (-5965 3410);
PAINT MONO (-5965 3410);
DISPLAY INVISIBLE (-5965 3410);
FORCEPROP 1 LASTPIN (-5975 3400) BN 2
J 2
(-5963 3408);
DISPLAY 0.489362 (-5963 3408);
PAINT GREEN (-5963 3408);
FORCEPROP 2 LAST CDS_LIB mstr_standard
J 0
(-6025 3400);
DISPLAY 0.723404 (-6025 3400);
PAINT MONO (-6025 3400);
DISPLAY INVISIBLE (-6025 3400);
FORCEPROP 1 LAST BODY_TYPE PLUMBING
J 2
(-6025 3450);
DISPLAY 0.872340 (-6025 3450);
PAINT GREEN (-6025 3450);
DISPLAY INVISIBLE (-6025 3450);
FORCEPROP 1 LAST HDL_TAP TRUE
J 2
(-6350 3275);
DISPLAY 0.872340 (-6350 3275);
DISPLAY INVISIBLE (-6350 3275);
FORCEPROP 1 LAST PATH I298
J 2
(-6023 3400);
DISPLAY 0.872340 (-6023 3400);
PAINT GREEN (-6023 3400);
DISPLAY INVISIBLE (-6023 3400);
FORCEADD TAP..1
R 2
(-6025 3300);
FORCEPROP 3 LASTPIN (-5975 3300) SIG_NAME M_E_CPU0_SB_CA<4>
J 0
(-5965 3310);
DISPLAY 0.659574 (-5965 3310);
PAINT MONO (-5965 3310);
DISPLAY INVISIBLE (-5965 3310);
FORCEPROP 1 LASTPIN (-5975 3300) BN 4
J 2
(-5963 3308);
DISPLAY 0.489362 (-5963 3308);
PAINT GREEN (-5963 3308);
FORCEPROP 2 LAST CDS_LIB mstr_standard
J 0
(-6025 3300);
DISPLAY 0.723404 (-6025 3300);
PAINT MONO (-6025 3300);
DISPLAY INVISIBLE (-6025 3300);
FORCEPROP 1 LAST BODY_TYPE PLUMBING
J 2
(-6025 3350);
DISPLAY 0.872340 (-6025 3350);
PAINT GREEN (-6025 3350);
DISPLAY INVISIBLE (-6025 3350);
FORCEPROP 1 LAST HDL_TAP TRUE
J 2
(-6350 3175);
DISPLAY 0.872340 (-6350 3175);
DISPLAY INVISIBLE (-6350 3175);
FORCEPROP 1 LAST PATH I299
J 2
(-6023 3300);
DISPLAY 0.872340 (-6023 3300);
PAINT GREEN (-6023 3300);
DISPLAY INVISIBLE (-6023 3300);
FORCEADD TAP..1
R 2
(-6025 3250);
FORCEPROP 3 LASTPIN (-5975 3250) SIG_NAME M_E_CPU0_SB_CA<5>
J 0
(-5965 3260);
DISPLAY 0.659574 (-5965 3260);
PAINT MONO (-5965 3260);
DISPLAY INVISIBLE (-5965 3260);
FORCEPROP 1 LASTPIN (-5975 3250) BN 5
J 2
(-5963 3258);
DISPLAY 0.489362 (-5963 3258);
PAINT GREEN (-5963 3258);
FORCEPROP 2 LAST CDS_LIB mstr_standard
J 0
(-6025 3250);
DISPLAY 0.723404 (-6025 3250);
PAINT MONO (-6025 3250);
DISPLAY INVISIBLE (-6025 3250);
FORCEPROP 1 LAST BODY_TYPE PLUMBING
J 2
(-6025 3300);
DISPLAY 0.872340 (-6025 3300);
PAINT GREEN (-6025 3300);
DISPLAY INVISIBLE (-6025 3300);
FORCEPROP 1 LAST HDL_TAP TRUE
J 2
(-6350 3125);
DISPLAY 0.872340 (-6350 3125);
DISPLAY INVISIBLE (-6350 3125);
FORCEPROP 1 LAST PATH I300
J 2
(-6023 3250);
DISPLAY 0.872340 (-6023 3250);
PAINT GREEN (-6023 3250);
DISPLAY INVISIBLE (-6023 3250);
FORCEADD TAP..1
R 2
(-6025 3200);
FORCEPROP 3 LASTPIN (-5975 3200) SIG_NAME M_E_CPU0_SB_CA<6>
J 0
(-5965 3210);
DISPLAY 0.659574 (-5965 3210);
PAINT MONO (-5965 3210);
DISPLAY INVISIBLE (-5965 3210);
FORCEPROP 1 LASTPIN (-5975 3200) BN 6
J 2
(-5963 3208);
DISPLAY 0.489362 (-5963 3208);
PAINT GREEN (-5963 3208);
FORCEPROP 2 LAST CDS_LIB mstr_standard
J 0
(-6025 3200);
DISPLAY 0.723404 (-6025 3200);
PAINT MONO (-6025 3200);
DISPLAY INVISIBLE (-6025 3200);
FORCEPROP 1 LAST BODY_TYPE PLUMBING
J 2
(-6025 3250);
DISPLAY 0.872340 (-6025 3250);
PAINT GREEN (-6025 3250);
DISPLAY INVISIBLE (-6025 3250);
FORCEPROP 1 LAST HDL_TAP TRUE
J 2
(-6350 3075);
DISPLAY 0.872340 (-6350 3075);
DISPLAY INVISIBLE (-6350 3075);
FORCEPROP 1 LAST PATH I301
J 2
(-6023 3200);
DISPLAY 0.872340 (-6023 3200);
PAINT GREEN (-6023 3200);
DISPLAY INVISIBLE (-6023 3200);
FORCEADD OFFPAGE..2
R 2
(-6625 3525);
FORCEPROP 2 LAST $XR0 89 
J 0
(-6849 3525);
DISPLAY 0.638298 (-6849 3525);
PAINT MONO (-6849 3525);
FORCEPROP 2 LAST PATH I302
J 0
(-6875 3575);
DISPLAY 1.021277 (-6875 3575);
DISPLAY INVISIBLE (-6875 3575);
FORCEPROP 1 LAST COMMENT_BODY TRUE
J 2
(-6580 3430);
DISPLAY 0.872340 (-6580 3430);
PAINT GREEN (-6580 3430);
DISPLAY INVISIBLE (-6580 3430);
FORCEPROP 1 LAST OFFPAGE TRUE
J 2
(-6950 3400);
DISPLAY 0.872340 (-6950 3400);
PAINT GREEN (-6950 3400);
DISPLAY INVISIBLE (-6950 3400);
FORCEPROP 2 LAST CDS_LIB standard
J 0
(-6625 3525);
DISPLAY INVISIBLE (-6625 3525);
FORCEADD OFFPAGE..2
R 2
(-6625 3925);
FORCEPROP 2 LAST $XR0 89 
J 0
(-6849 3925);
DISPLAY 0.638298 (-6849 3925);
PAINT MONO (-6849 3925);
FORCEPROP 2 LAST PATH I303
J 0
(-6875 3975);
DISPLAY 1.021277 (-6875 3975);
DISPLAY INVISIBLE (-6875 3975);
FORCEPROP 1 LAST COMMENT_BODY TRUE
J 2
(-6580 3830);
DISPLAY 0.872340 (-6580 3830);
PAINT GREEN (-6580 3830);
DISPLAY INVISIBLE (-6580 3830);
FORCEPROP 1 LAST OFFPAGE TRUE
J 2
(-6950 3800);
DISPLAY 0.872340 (-6950 3800);
PAINT GREEN (-6950 3800);
DISPLAY INVISIBLE (-6950 3800);
FORCEPROP 2 LAST CDS_LIB standard
J 0
(-6625 3925);
DISPLAY INVISIBLE (-6625 3925);
FORCEADD OFFPAGE..2
R 2
(-6625 2850);
FORCEPROP 2 LAST $XR0 89 
J 0
(-6849 2850);
DISPLAY 0.638298 (-6849 2850);
PAINT MONO (-6849 2850);
FORCEPROP 2 LAST PATH I304
J 0
(-6875 2900);
DISPLAY 1.021277 (-6875 2900);
DISPLAY INVISIBLE (-6875 2900);
FORCEPROP 1 LAST COMMENT_BODY TRUE
J 2
(-6580 2755);
DISPLAY 0.872340 (-6580 2755);
PAINT GREEN (-6580 2755);
DISPLAY INVISIBLE (-6580 2755);
FORCEPROP 1 LAST OFFPAGE TRUE
J 2
(-6950 2725);
DISPLAY 0.872340 (-6950 2725);
PAINT GREEN (-6950 2725);
DISPLAY INVISIBLE (-6950 2725);
FORCEPROP 2 LAST CDS_LIB standard
J 0
(-6625 2850);
DISPLAY INVISIBLE (-6625 2850);
FORCEADD OFFPAGE..2
R 2
(-6625 2900);
FORCEPROP 2 LAST $XR0 89 
J 0
(-6849 2900);
DISPLAY 0.638298 (-6849 2900);
PAINT MONO (-6849 2900);
FORCEPROP 2 LAST PATH I305
J 0
(-6875 2950);
DISPLAY 1.021277 (-6875 2950);
DISPLAY INVISIBLE (-6875 2950);
FORCEPROP 1 LAST COMMENT_BODY TRUE
J 2
(-6580 2805);
DISPLAY 0.872340 (-6580 2805);
PAINT GREEN (-6580 2805);
DISPLAY INVISIBLE (-6580 2805);
FORCEPROP 1 LAST OFFPAGE TRUE
J 2
(-6950 2775);
DISPLAY 0.872340 (-6950 2775);
PAINT GREEN (-6950 2775);
DISPLAY INVISIBLE (-6950 2775);
FORCEPROP 2 LAST CDS_LIB standard
J 0
(-6625 2900);
DISPLAY INVISIBLE (-6625 2900);
FORCEADD OFFPAGE..2
R 2
(-6625 3000);
FORCEPROP 2 LAST $XR0 89 
J 0
(-6849 3000);
DISPLAY 0.638298 (-6849 3000);
PAINT MONO (-6849 3000);
FORCEPROP 2 LAST PATH I306
J 0
(-6875 3050);
DISPLAY 1.021277 (-6875 3050);
DISPLAY INVISIBLE (-6875 3050);
FORCEPROP 1 LAST COMMENT_BODY TRUE
J 2
(-6580 2905);
DISPLAY 0.872340 (-6580 2905);
PAINT GREEN (-6580 2905);
DISPLAY INVISIBLE (-6580 2905);
FORCEPROP 1 LAST OFFPAGE TRUE
J 2
(-6950 2875);
DISPLAY 0.872340 (-6950 2875);
PAINT GREEN (-6950 2875);
DISPLAY INVISIBLE (-6950 2875);
FORCEPROP 2 LAST CDS_LIB standard
J 0
(-6625 3000);
DISPLAY INVISIBLE (-6625 3000);
FORCEADD OFFPAGE..2
R 2
(-6625 3050);
FORCEPROP 2 LAST $XR0 89 
J 0
(-6849 3050);
DISPLAY 0.638298 (-6849 3050);
PAINT MONO (-6849 3050);
FORCEPROP 2 LAST PATH I307
J 0
(-6875 3100);
DISPLAY 1.021277 (-6875 3100);
DISPLAY INVISIBLE (-6875 3100);
FORCEPROP 1 LAST COMMENT_BODY TRUE
J 2
(-6580 2955);
DISPLAY 0.872340 (-6580 2955);
PAINT GREEN (-6580 2955);
DISPLAY INVISIBLE (-6580 2955);
FORCEPROP 1 LAST OFFPAGE TRUE
J 2
(-6950 2925);
DISPLAY 0.872340 (-6950 2925);
PAINT GREEN (-6950 2925);
DISPLAY INVISIBLE (-6950 2925);
FORCEPROP 2 LAST CDS_LIB standard
J 0
(-6625 3050);
DISPLAY INVISIBLE (-6625 3050);
FORCEADD OFFPAGE..5
(-6625 2100);
FORCEPROP 2 LAST $XR0 89 
J 0
(-6849 2100);
DISPLAY 0.638298 (-6849 2100);
PAINT MONO (-6849 2100);
FORCEPROP 2 LAST PATH I308
J 0
(-6875 2150);
DISPLAY 1.021277 (-6875 2150);
DISPLAY INVISIBLE (-6875 2150);
FORCEPROP 1 LAST COMMENT_BODY TRUE
J 0
(-6525 2025);
DISPLAY 0.872340 (-6525 2025);
PAINT GREEN (-6525 2025);
DISPLAY INVISIBLE (-6525 2025);
FORCEPROP 1 LAST OFFPAGE TRUE
J 0
(-6300 1975);
DISPLAY 0.872340 (-6300 1975);
PAINT GREEN (-6300 1975);
DISPLAY INVISIBLE (-6300 1975);
FORCEPROP 2 LAST CDS_LIB standard
J 0
(-6625 2100);
DISPLAY INVISIBLE (-6625 2100);
FORCEADD OFFPAGE..5
(-6625 2300);
FORCEPROP 2 LAST $XR0 89 
J 0
(-6849 2300);
DISPLAY 0.638298 (-6849 2300);
PAINT MONO (-6849 2300);
FORCEPROP 2 LAST PATH I309
J 0
(-6875 2350);
DISPLAY 1.021277 (-6875 2350);
DISPLAY INVISIBLE (-6875 2350);
FORCEPROP 1 LAST COMMENT_BODY TRUE
J 0
(-6525 2225);
DISPLAY 0.872340 (-6525 2225);
PAINT GREEN (-6525 2225);
DISPLAY INVISIBLE (-6525 2225);
FORCEPROP 1 LAST OFFPAGE TRUE
J 0
(-6300 2175);
DISPLAY 0.872340 (-6300 2175);
PAINT GREEN (-6300 2175);
DISPLAY INVISIBLE (-6300 2175);
FORCEPROP 2 LAST CDS_LIB standard
J 0
(-6625 2300);
DISPLAY INVISIBLE (-6625 2300);
FORCEADD OFFPAGE..2
R 2
(-6625 2500);
FORCEPROP 2 LAST $XR0 89 
J 0
(-6849 2500);
DISPLAY 0.638298 (-6849 2500);
PAINT MONO (-6849 2500);
FORCEPROP 2 LAST PATH I310
J 0
(-6875 2550);
DISPLAY 1.021277 (-6875 2550);
DISPLAY INVISIBLE (-6875 2550);
FORCEPROP 1 LAST COMMENT_BODY TRUE
J 2
(-6580 2405);
DISPLAY 0.872340 (-6580 2405);
PAINT GREEN (-6580 2405);
DISPLAY INVISIBLE (-6580 2405);
FORCEPROP 1 LAST OFFPAGE TRUE
J 2
(-6950 2375);
DISPLAY 0.872340 (-6950 2375);
PAINT GREEN (-6950 2375);
DISPLAY INVISIBLE (-6950 2375);
FORCEPROP 2 LAST CDS_LIB standard
J 0
(-6625 2500);
DISPLAY INVISIBLE (-6625 2500);
FORCEADD OFFPAGE..2
R 2
(-6625 2550);
FORCEPROP 2 LAST $XR0 89 
J 0
(-6849 2550);
DISPLAY 0.638298 (-6849 2550);
PAINT MONO (-6849 2550);
FORCEPROP 2 LAST PATH I311
J 0
(-6875 2600);
DISPLAY 1.021277 (-6875 2600);
DISPLAY INVISIBLE (-6875 2600);
FORCEPROP 1 LAST COMMENT_BODY TRUE
J 2
(-6580 2455);
DISPLAY 0.872340 (-6580 2455);
PAINT GREEN (-6580 2455);
DISPLAY INVISIBLE (-6580 2455);
FORCEPROP 1 LAST OFFPAGE TRUE
J 2
(-6950 2425);
DISPLAY 0.872340 (-6950 2425);
PAINT GREEN (-6950 2425);
DISPLAY INVISIBLE (-6950 2425);
FORCEPROP 2 LAST CDS_LIB standard
J 0
(-6625 2550);
DISPLAY INVISIBLE (-6625 2550);
FORCEADD OFFPAGE..5
(-6625 2650);
FORCEPROP 2 LAST $XR0 89 
J 0
(-6849 2650);
DISPLAY 0.638298 (-6849 2650);
PAINT MONO (-6849 2650);
FORCEPROP 2 LAST PATH I312
J 0
(-6875 2700);
DISPLAY 1.021277 (-6875 2700);
DISPLAY INVISIBLE (-6875 2700);
FORCEPROP 1 LAST COMMENT_BODY TRUE
J 0
(-6525 2575);
DISPLAY 0.872340 (-6525 2575);
PAINT GREEN (-6525 2575);
DISPLAY INVISIBLE (-6525 2575);
FORCEPROP 1 LAST OFFPAGE TRUE
J 0
(-6300 2525);
DISPLAY 0.872340 (-6300 2525);
PAINT GREEN (-6300 2525);
DISPLAY INVISIBLE (-6300 2525);
FORCEPROP 2 LAST CDS_LIB mstr_standard
J 0
(-6625 2650);
DISPLAY INVISIBLE (-6625 2650);
FORCEADD OFFPAGE..1
(-6625 2750);
FORCEPROP 2 LAST $XR0 89 
J 0
(-6846 2750);
DISPLAY 0.638298 (-6846 2750);
PAINT MONO (-6846 2750);
FORCEPROP 2 LAST PATH I313
J 0
(-6875 2800);
DISPLAY 1.021277 (-6875 2800);
DISPLAY INVISIBLE (-6875 2800);
FORCEPROP 1 LAST COMMENT_BODY TRUE
J 0
(-6500 2650);
DISPLAY 0.872340 (-6500 2650);
PAINT GREEN (-6500 2650);
DISPLAY INVISIBLE (-6500 2650);
FORCEPROP 1 LAST OFFPAGE TRUE
J 0
(-6300 2625);
DISPLAY 0.872340 (-6300 2625);
PAINT GREEN (-6300 2625);
DISPLAY INVISIBLE (-6300 2625);
FORCEPROP 2 LAST CDS_LIB standard
J 0
(-6625 2750);
DISPLAY INVISIBLE (-6625 2750);
FORCEADD OFFPAGE..1
(-6625 2400);
FORCEPROP 2 LAST $XR0 89 
J 0
(-6846 2400);
DISPLAY 0.638298 (-6846 2400);
PAINT MONO (-6846 2400);
FORCEPROP 2 LAST PATH I314
J 0
(-6875 2450);
DISPLAY 1.021277 (-6875 2450);
DISPLAY INVISIBLE (-6875 2450);
FORCEPROP 1 LAST COMMENT_BODY TRUE
J 0
(-6500 2300);
DISPLAY 0.872340 (-6500 2300);
PAINT GREEN (-6500 2300);
DISPLAY INVISIBLE (-6500 2300);
FORCEPROP 1 LAST OFFPAGE TRUE
J 0
(-6300 2275);
DISPLAY 0.872340 (-6300 2275);
PAINT GREEN (-6300 2275);
DISPLAY INVISIBLE (-6300 2275);
FORCEPROP 2 LAST CDS_LIB standard
J 0
(-6625 2400);
DISPLAY INVISIBLE (-6625 2400);
FORCEADD Q_RES..1
(-6950 2200);
FORCEPROP 1 LAST LOCATION R379
J 0
(-7275 2200);
DISPLAY 0.489362 (-7275 2200);
PAINT SKYBLUE (-7275 2200);
FORCEPROP 0 LAST $SEC 1
J 0
(-7125 2250);
DISPLAY 0.680851 (-7125 2250);
PAINT MONO (-7125 2250);
DISPLAY INVISIBLE (-7125 2250);
FORCEPROP 0 LAST CDS_SEC 1
J 0
(-7125 2250);
DISPLAY 1.021277 (-7125 2250);
DISPLAY INVISIBLE (-7125 2250);
FORCEPROP 1 LASTPIN (-7050 2200) $PN 1
J 0
(-7038 2212);
DISPLAY 0.489362 (-7038 2212);
PAINT MONO (-7038 2212);
FORCEPROP 1 LASTPIN (-6850 2200) $PN 2
J 0
(-6888 2212);
DISPLAY 0.489362 (-6888 2212);
PAINT MONO (-6888 2212);
FORCEPROP 1 LAST TOLERANCE 1%
J 0
(-6675 2200);
DISPLAY 0.489362 (-6675 2200);
PAINT SKYBLUE (-6675 2200);
FORCEPROP 1 LAST VALUE 15   
J 2
(-6625 2200);
DISPLAY 0.489362 (-6625 2200);
PAINT SKYBLUE (-6625 2200);
FORCEPROP 1 LAST PART_NUMBER CS01502FB11
J 0
(-6850 2175);
DISPLAY 0.489362 (-6850 2175);
PAINT SKYBLUE (-6850 2175);
FORCEPROP 1 LAST PACK_TYPE 0402LF
J 0
(-7275 2175);
DISPLAY 0.489362 (-7275 2175);
PAINT SKYBLUE (-7275 2175);
FORCEPROP 2 LAST CDS_LIB pure_quanta
J 0
(-6950 2200);
DISPLAY INVISIBLE (-6950 2200);
FORCEPROP 1 LAST PATH I315
J 0
(-7000 2350);
DISPLAY 0.978723 (-7000 2350);
PAINT WHITE (-7000 2350);
DISPLAY INVISIBLE (-7000 2350);
FORCEPROP 1 LAST WATTAGE 1/16W
J 2
(-6725 2325);
DISPLAY 0.638298 (-6725 2325);
PAINT SKYBLUE (-6725 2325);
DISPLAY INVISIBLE (-6725 2325);
FORCEPROP 1 LAST MATERIAL CHIP
J 0
(-7075 2325);
DISPLAY 0.638298 (-7075 2325);
PAINT SKYBLUE (-7075 2325);
DISPLAY INVISIBLE (-7075 2325);
FORCEADD OFFPAGE..1
(-7825 2200);
FORCEPROP 2 LAST $XR0 89 
J 0
(-8046 2200);
DISPLAY 0.638298 (-8046 2200);
PAINT MONO (-8046 2200);
FORCEPROP 2 LAST PATH I316
J 0
(-8075 2250);
DISPLAY 1.021277 (-8075 2250);
DISPLAY INVISIBLE (-8075 2250);
FORCEPROP 1 LAST COMMENT_BODY TRUE
J 0
(-7700 2100);
DISPLAY 0.872340 (-7700 2100);
PAINT GREEN (-7700 2100);
DISPLAY INVISIBLE (-7700 2100);
FORCEPROP 1 LAST OFFPAGE TRUE
J 0
(-7500 2075);
DISPLAY 0.872340 (-7500 2075);
PAINT GREEN (-7500 2075);
DISPLAY INVISIBLE (-7500 2075);
FORCEPROP 2 LAST CDS_LIB mstr_standard
J 0
(-7825 2200);
DISPLAY INVISIBLE (-7825 2200);
FORCEADD QUANTA_TITLE_BLOCK_C..1
(-100 100);
FORCEPROP 0 LAST CDS_CON_LAST_MODIFIED Fri Mar 11 14:52:13 2022
J 0
(-1985 115);
DISPLAY INVISIBLE (-1985 115);
FORCEPROP 1 LAST CUSTOM_TXT_CDS <CON_LAST_MODIFIED>
J 0
(-1985 115);
DISPLAY 0.978723 (-1985 115);
FORCEPROP 2 LAST CUSTOM_TXT_CDS <XR_PAGE_TITLE>
J 0
(-7990 5350);
DISPLAY 0.638298 (-7990 5350);
PAINT PINK (-7990 5350);
DISPLAY INVISIBLE (-7990 5350);
FORCEPROP 1 LAST CUSTOM_TXT_CDS <NAME_2>
J 0
(-3275 150);
FORCEPROP 1 LAST CUSTOM_TXT_CDS <NAME_1>
J 0
(-3275 275);
FORCEPROP 1 LAST CUSTOM_TXT_CDS <Q_NUMBER>
J 0
(-1503 203);
DISPLAY 1.212766 (-1503 203);
FORCEPROP 1 LAST CUSTOM_TXT_CDS <Q_PROJ>
J 0
(-2482 202);
DISPLAY 1.212766 (-2482 202);
FORCEPROP 1 LAST CUSTOM_TXT_CDS <Q_REV>
J 0
(-284 203);
DISPLAY 1.212766 (-284 203);
FORCEPROP 1 LAST CUSTOM_TXT_CDS <CON_PAGE_NUM> OF <CON_TOTAL_PAGES>
J 0
(-546 118);
DISPLAY 0.978723 (-546 118);
FORCEPROP 1 LAST Q_TITLE CPU0 DDR CHE
J 0
(-9425 150);
DISPLAY 2.446809 (-9425 150);
PAINT GREEN (-9425 150);
FORCEPROP 1 LAST Q_DEPT BU9
J 1
(-3863 149);
DISPLAY 1.957447 (-3863 149);
PAINT GREEN (-3863 149);
FORCEPROP 2 LAST PAGE_BORDER TRUE
J 0
(-7990 5350);
DISPLAY 0.638298 (-7990 5350);
PAINT PINK (-7990 5350);
DISPLAY INVISIBLE (-7990 5350);
FORCEPROP 1 LAST CDS_LMAN_SYM_OUTLINE -9475,6775,100,-125
J 0
(-100 100);
DISPLAY 0.468085 (-100 100);
PAINT GREEN (-100 100);
DISPLAY INVISIBLE (-100 100);
FORCEPROP 2 LAST CDS_LIB pure_quanta
J 0
(-100 100);
DISPLAY INVISIBLE (-100 100);
FORCEPROP 1 LAST COMMENT_BODY TRUE
J 0
(-88 87);
DISPLAY 0.978723 (-88 87);
PAINT GREEN (-88 87);
DISPLAY INVISIBLE (-88 87);
FORCEPROP 2 LAST CDS_XR_PAGE_TITLE CR-14 : @T6G_MB_LIB.T6G(SCH_1):PAGE14
J 0
(-7990 5350);
DISPLAY 0.638298 (-7990 5350);
PAINT PINK (-7990 5350);
DISPLAY INVISIBLE (-7990 5350);
FORCEADD CAD_NOTE..1
(-7725 2475);
FORCEPROP 0 LAST L1 R1953 PLACE CLOSE TO CPU < 25MM
J 0
(-7875 2350);
DISPLAY 0.617021 (-7875 2350);
PAINT WHITE (-7875 2350);
FORCEPROP 2 LAST CDS_LIB pure_quanta_power
J 0
(-7725 2475);
DISPLAY INVISIBLE (-7725 2475);
FORCEPROP 1 LAST COMMENT_BODY TRUE
J 0
(-7700 2575);
DISPLAY 0.574468 (-7700 2575);
PAINT WHITE (-7700 2575);
DISPLAY INVISIBLE (-7700 2575);
WIRE 17 -1 (-3350 6075)(-3350 6025);
WIRE 17 -1 (-3350 6075)(-2725 6075);
FORCEPROP 2 LAST SIG_NAME M_E_CPU0_SA_DQ<31:0>
J 2
(-2785 6085);
DISPLAY 0.489362 (-2785 6085);
WIRE 17 -1 (-3350 6025)(-3350 5975);
WIRE 17 -1 (-3350 5975)(-3350 5925);
WIRE 17 -1 (-3350 5925)(-3350 5875);
WIRE 17 -1 (-3350 5875)(-3350 5825);
WIRE 17 -1 (-3350 5525)(-3350 5475);
WIRE 17 -1 (-3350 5575)(-3350 5525);
WIRE 17 -1 (-3350 5475)(-3350 5425);
WIRE 17 -1 (-3350 5425)(-3350 5375);
WIRE 17 -1 (-3350 5625)(-3350 5575);
WIRE 17 -1 (-3350 5725)(-3350 5625);
WIRE 17 -1 (-3350 5375)(-3350 5325);
WIRE 17 -1 (-3350 5325)(-3350 5275);
WIRE 17 -1 (-3350 5775)(-3350 5725);
WIRE 17 -1 (-3350 5825)(-3350 5775);
WIRE 17 -1 (-3350 5175)(-3350 5275);
WIRE 17 -1 (-3350 5125)(-3350 5175);
WIRE 17 -1 (-3350 5075)(-3350 5125);
WIRE 17 -1 (-3350 5025)(-3350 5075);
WIRE 17 -1 (-3350 5025)(-3350 4975);
WIRE 17 -1 (-3350 4975)(-3350 4925);
WIRE 17 -1 (-3350 4925)(-3350 4875);
WIRE 17 -1 (-3350 4875)(-3350 4825);
WIRE 17 -1 (-3350 4825)(-3350 4725);
WIRE 17 -1 (-3350 4725)(-3350 4675);
WIRE 17 -1 (-3350 4675)(-3350 4625);
WIRE 17 -1 (-3350 4625)(-3350 4575);
WIRE 17 -1 (-3350 4525)(-3350 4575);
WIRE 17 -1 (-3350 4475)(-3350 4525);
WIRE 17 -1 (-3350 4425)(-3350 4475);
WIRE 17 -1 (-3350 4375)(-3350 4425);
WIRE 17 -1 (-3350 4275)(-3350 4225);
WIRE 17 -1 (-3350 4275)(-2725 4275);
FORCEPROP 2 LAST SIG_NAME M_E_CPU0_SB_DQ<31:0>
J 2
(-2785 4285);
DISPLAY 0.489362 (-2785 4285);
WIRE 17 -1 (-3350 4225)(-3350 4175);
WIRE 17 -1 (-3350 4175)(-3350 4125);
WIRE 17 -1 (-3350 4125)(-3350 4075);
WIRE 17 -1 (-3350 4075)(-3350 4025);
WIRE 17 -1 (-3350 4025)(-3350 3975);
WIRE 17 -1 (-3350 3975)(-3350 3925);
WIRE 17 -1 (-3350 3925)(-3350 3825);
WIRE 17 -1 (-3350 3375)(-3350 3475);
WIRE 17 -1 (-3350 3325)(-3350 3375);
WIRE 17 -1 (-3350 3525)(-3350 3475);
WIRE 17 -1 (-3350 3575)(-3350 3525);
WIRE 17 -1 (-3350 3275)(-3350 3325);
WIRE 17 -1 (-3350 3225)(-3350 3275);
WIRE 17 -1 (-3350 3625)(-3350 3575);
WIRE 17 -1 (-3350 3675)(-3350 3625);
WIRE 17 -1 (-3350 3225)(-3350 3175);
WIRE 17 -1 (-3350 3175)(-3350 3125);
WIRE 17 -1 (-3350 3725)(-3350 3675);
WIRE 17 -1 (-3350 3775)(-3350 3725);
WIRE 17 -1 (-3350 3125)(-3350 3075);
WIRE 17 -1 (-3350 3075)(-3350 3025);
WIRE 17 -1 (-3350 3825)(-3350 3775);
WIRE 17 -1 (-3350 3025)(-3350 2925);
WIRE 17 -1 (-3350 2925)(-3350 2875);
WIRE 17 -1 (-3350 2875)(-3350 2825);
WIRE 17 -1 (-3350 2825)(-3350 2775);
WIRE 17 -1 (-3350 2725)(-3350 2775);
WIRE 17 -1 (-3350 2675)(-3350 2725);
WIRE 17 -1 (-3350 2625)(-3350 2675);
WIRE 17 -1 (-3350 2575)(-3350 2625);
WIRE 17 -1 (-3350 2475)(-3350 2425);
WIRE 17 -1 (-3350 2475)(-3350 2500);
WIRE 17 -1 (-3350 2375)(-3350 2425);
WIRE 17 -1 (-3350 2375)(-3350 2325);
WIRE 17 -1 (-3350 2500)(-2850 2500);
FORCEPROP 2 LAST SIG_NAME M_E_CPU0_SA_CB<7:0>
J 2
(-2850 2510);
DISPLAY 0.489362 (-2850 2510);
WIRE 17 -1 (-3350 2275)(-3350 2325);
WIRE 17 -1 (-3350 2225)(-3350 2275);
WIRE 17 -1 (-3350 2175)(-3350 2225);
WIRE 17 -1 (-3350 2125)(-3350 2175);
WIRE 17 -1 (-3350 1725)(-3350 1775);
WIRE 17 -1 (-3350 1675)(-3350 1725);
WIRE 17 -1 (-3350 1775)(-3350 1825);
WIRE 17 -1 (-3350 1825)(-3350 1875);
WIRE 17 -1 (-3350 1925)(-3350 1875);
WIRE 17 -1 (-3350 1925)(-3350 1975);
WIRE 17 -1 (-3350 2025)(-3350 1975);
WIRE 17 -1 (-3350 2025)(-3350 2050);
WIRE 17 -1 (-3350 2050)(-2850 2050);
FORCEPROP 2 LAST SIG_NAME M_E_CPU0_SB_CB<7:0>
J 2
(-2850 2060);
DISPLAY 0.489362 (-2850 2060);
WIRE 17 -1 (-6075 5325)(-6075 5225);
WIRE 17 -1 (-6075 5325)(-6075 5425);
WIRE 17 -1 (-6075 5225)(-6075 5125);
WIRE 17 -1 (-6075 5425)(-6075 5525);
WIRE 17 -1 (-6075 5525)(-6075 5625);
WIRE 17 -1 (-6075 5725)(-6075 5625);
WIRE 17 -1 (-6075 5825)(-6075 5725);
WIRE 17 -1 (-6075 5925)(-6075 5825);
WIRE 17 -1 (-6075 6025)(-6075 5925);
FORCEPROP 2 LAST SIG_NAME M_E_CPU0_SA_DQS_DN<9:0>
J 2
(-6110 6035);
DISPLAY 0.489362 (-6110 6035);
WIRE 17 -1 (-5875 5775)(-5875 5675);
WIRE 17 -1 (-5875 5875)(-5875 5775);
WIRE 17 -1 (-5875 5575)(-5875 5675);
WIRE 17 -1 (-5875 5475)(-5875 5575);
WIRE 17 -1 (-5875 5975)(-5875 5875);
WIRE 17 -1 (-5875 6075)(-5875 5975);
WIRE 17 -1 (-5875 5375)(-5875 5475);
WIRE 17 -1 (-5875 5375)(-5875 5275);
WIRE 17 -1 (-5875 6075)(-6675 6075);
FORCEPROP 2 LAST SIG_NAME M_E_CPU0_SA_DQS_DP<9:0>
J 2
(-6110 6085);
DISPLAY 0.489362 (-6110 6085);
WIRE 17 -1 (-5875 5275)(-5875 5175);
WIRE 17 -1 (-6075 4775)(-6075 4675);
WIRE 17 -1 (-6075 4875)(-6075 4775);
WIRE 17 -1 (-6075 4675)(-6075 4575);
WIRE 17 -1 (-6075 4475)(-6075 4575);
WIRE 17 -1 (-6075 4975)(-6075 4875);
FORCEPROP 2 LAST SIG_NAME M_E_CPU0_SB_DQS_DN<9:0>
J 2
(-6110 4985);
DISPLAY 0.489362 (-6110 4985);
WIRE 17 -1 (-6075 4375)(-6075 4475);
WIRE 17 -1 (-6075 4275)(-6075 4375);
WIRE 17 -1 (-6075 4275)(-6075 4175);
WIRE 17 -1 (-5875 5025)(-5875 4925);
WIRE 17 -1 (-5875 5025)(-6675 5025);
FORCEPROP 2 LAST SIG_NAME M_E_CPU0_SB_DQS_DP<9:0>
J 2
(-6110 5035);
DISPLAY 0.489362 (-6110 5035);
WIRE 17 -1 (-6075 4175)(-6075 4075);
WIRE 17 -1 (-5875 4925)(-5875 4825);
WIRE 17 -1 (-5875 4825)(-5875 4725);
WIRE 17 -1 (-5875 4725)(-5875 4625);
WIRE 17 -1 (-5875 4525)(-5875 4625);
WIRE 17 -1 (-5875 4425)(-5875 4525);
WIRE 17 -1 (-5875 4325)(-5875 4425);
WIRE 17 -1 (-5875 4325)(-5875 4225);
WIRE 17 -1 (-5875 4225)(-5875 4125);
WIRE 17 -1 (-6075 3875)(-6075 3925);
WIRE 17 -1 (-6075 3825)(-6075 3875);
WIRE 17 -1 (-6075 3925)(-6575 3925);
FORCEPROP 2 LAST SIG_NAME M_E_CPU0_SA_CA<6:0>
J 0
(-6575 3935);
DISPLAY 0.489362 (-6575 3935);
WIRE 17 -1 (-6075 3475)(-6075 3525);
WIRE 17 -1 (-6075 3425)(-6075 3475);
WIRE 17 -1 (-6075 3525)(-6575 3525);
FORCEPROP 2 LAST SIG_NAME M_E_CPU0_SB_CA<6:0>
J 0
(-6575 3535);
DISPLAY 0.489362 (-6575 3535);
WIRE 17 -1 (-6075 3775)(-6075 3825);
WIRE 17 -1 (-6075 3375)(-6075 3425);
WIRE 17 -1 (-6075 3725)(-6075 3775);
WIRE 17 -1 (-6075 3675)(-6075 3725);
WIRE 17 -1 (-6075 3625)(-6075 3675);
WIRE 17 -1 (-6075 3325)(-6075 3375);
WIRE 17 -1 (-6075 3275)(-6075 3325);
WIRE 17 -1 (-6075 3225)(-6075 3275);
WIRE 17 -1 (-6075 6025)(-6675 6025);
WIRE 17 -1 (-6075 4975)(-6675 4975);
WIRE 16 -1 (-7775 2200)(-7050 2200);
FORCEPROP 2 LAST SIG_NAME M_E_CPU0_ALERT_N
J 0
(-7735 2210);
DISPLAY 0.489362 (-7735 2210);
WIRE 16 -1 (-6575 1250)(-5475 1250);
FORCEPROP 2 LAST SIG_NAME TP_M_E_CPU0_SA_TEST39E
J 0
(-6560 1260);
DISPLAY 0.489362 (-6560 1260);
FORCEPROP 2 LASTPROP $XRERR UNIQUE?
J 0
(-6815 1250);
DISPLAY 0.638298 (-6815 1250);
PAINT MONO (-6815 1250);
DISPLAY INVISIBLE (-6815 1250);
WIRE 16 -1 (-6850 2200)(-5475 2200);
FORCEPROP 2 LAST SIG_NAME M_E_CPU0_ALERT_R_N
J 0
(-6560 2210);
DISPLAY 0.489362 (-6560 2210);
FORCEPROP 2 LASTPROP $XRERR UNIQUE?
J 0
(-6800 2210);
DISPLAY 0.638298 (-6800 2210);
PAINT MONO (-6800 2210);
DISPLAY INVISIBLE (-6800 2210);
WIRE 16 -1 (-6575 2850)(-5475 2850);
FORCEPROP 2 LAST SIG_NAME M_E_CPU0_SA_CS_N<1>
J 0
(-6575 2860);
DISPLAY 0.489362 (-6575 2860);
WIRE 16 -1 (-6575 2900)(-5475 2900);
FORCEPROP 2 LAST SIG_NAME M_E_CPU0_SA_CS_N<0>
J 0
(-6575 2910);
DISPLAY 0.489362 (-6575 2910);
WIRE 16 -1 (-6575 3000)(-5475 3000);
FORCEPROP 2 LAST SIG_NAME M_E_CPU0_CLK_DN<0>
J 0
(-6575 3010);
DISPLAY 0.489362 (-6575 3010);
WIRE 16 -1 (-6575 3050)(-5475 3050);
FORCEPROP 2 LAST SIG_NAME M_E_CPU0_CLK_DP<0>
J 0
(-6575 3060);
DISPLAY 0.489362 (-6575 3060);
WIRE 16 -1 (-6575 2100)(-5475 2100);
FORCEPROP 2 LAST SIG_NAME M_E_CPU0_RESET_N
J 0
(-6575 2110);
DISPLAY 0.489362 (-6575 2110);
WIRE 16 -1 (-6575 2300)(-5475 2300);
FORCEPROP 2 LAST SIG_NAME M_E_CPU0_SB_PAR
J 0
(-6575 2310);
DISPLAY 0.489362 (-6575 2310);
WIRE 16 -1 (-6575 2500)(-5475 2500);
FORCEPROP 2 LAST SIG_NAME M_E_CPU0_SB_CS_N<1>
J 0
(-6575 2510);
DISPLAY 0.489362 (-6575 2510);
WIRE 16 -1 (-6575 2550)(-5475 2550);
FORCEPROP 2 LAST SIG_NAME M_E_CPU0_SB_CS_N<0>
J 0
(-6575 2560);
DISPLAY 0.489362 (-6575 2560);
WIRE 16 -1 (-6575 2650)(-5475 2650);
FORCEPROP 2 LAST SIG_NAME M_E_CPU0_SA_PAR
J 0
(-6575 2660);
DISPLAY 0.489362 (-6575 2660);
WIRE 16 -1 (-6575 2750)(-5475 2750);
FORCEPROP 2 LAST SIG_NAME M_E_CPU0_SA_RSP<0>
J 0
(-6575 2760);
DISPLAY 0.489362 (-6575 2760);
WIRE 16 -1 (-6575 2400)(-5475 2400);
FORCEPROP 2 LAST SIG_NAME M_E_CPU0_SB_RSP<0>
J 0
(-6575 2410);
DISPLAY 0.489362 (-6575 2410);
WIRE 16 -1 (-5975 3200)(-5475 3200);
WIRE 16 -1 (-5975 3600)(-5475 3600);
WIRE 16 -1 (-5975 3250)(-5475 3250);
WIRE 16 -1 (-5975 3650)(-5475 3650);
WIRE 16 -1 (-5975 3300)(-5475 3300);
WIRE 16 -1 (-5975 3700)(-5475 3700);
WIRE 16 -1 (-5975 3350)(-5475 3350);
WIRE 16 -1 (-5975 3750)(-5475 3750);
WIRE 16 -1 (-5975 3400)(-5475 3400);
WIRE 16 -1 (-5975 3800)(-5475 3800);
WIRE 16 -1 (-5975 3450)(-5475 3450);
WIRE 16 -1 (-5975 4050)(-5475 4050);
WIRE 16 -1 (-5975 3850)(-5475 3850);
WIRE 16 -1 (-5975 3500)(-5475 3500);
WIRE 16 -1 (-5975 3900)(-5475 3900);
WIRE 16 -1 (-5775 4100)(-5475 4100);
WIRE 16 -1 (-5975 4850)(-5475 4850);
WIRE 16 -1 (-5975 4950)(-5475 4950);
WIRE 16 -1 (-5775 4200)(-5475 4200);
WIRE 16 -1 (-5775 4300)(-5475 4300);
WIRE 16 -1 (-5775 4400)(-5475 4400);
WIRE 16 -1 (-5775 4500)(-5475 4500);
WIRE 16 -1 (-5775 4600)(-5475 4600);
WIRE 16 -1 (-5975 4150)(-5475 4150);
WIRE 16 -1 (-5775 4700)(-5475 4700);
WIRE 16 -1 (-5975 4250)(-5475 4250);
WIRE 16 -1 (-5775 4800)(-5475 4800);
WIRE 16 -1 (-5975 4350)(-5475 4350);
WIRE 16 -1 (-5775 4900)(-5475 4900);
WIRE 16 -1 (-5975 4450)(-5475 4450);
WIRE 16 -1 (-5775 5000)(-5475 5000);
WIRE 16 -1 (-5975 4550)(-5475 4550);
WIRE 16 -1 (-5975 5100)(-5475 5100);
WIRE 16 -1 (-5975 4650)(-5475 4650);
WIRE 16 -1 (-5975 4750)(-5475 4750);
WIRE 16 -1 (-5775 5750)(-5475 5750);
WIRE 16 -1 (-5975 5300)(-5475 5300);
WIRE 16 -1 (-5775 5850)(-5475 5850);
WIRE 16 -1 (-5975 5400)(-5475 5400);
WIRE 16 -1 (-5775 5950)(-5475 5950);
WIRE 16 -1 (-5975 5500)(-5475 5500);
WIRE 16 -1 (-5775 6050)(-5475 6050);
WIRE 16 -1 (-5975 5600)(-5475 5600);
WIRE 16 -1 (-5975 5700)(-5475 5700);
WIRE 16 -1 (-5975 5800)(-5475 5800);
WIRE 16 -1 (-5975 5900)(-5475 5900);
WIRE 16 -1 (-5975 6000)(-5475 6000);
WIRE 16 -1 (-5775 5150)(-5475 5150);
WIRE 16 -1 (-5775 5250)(-5475 5250);
WIRE 16 -1 (-5775 5350)(-5475 5350);
WIRE 16 -1 (-5775 5450)(-5475 5450);
WIRE 16 -1 (-5775 5550)(-5475 5550);
WIRE 16 -1 (-5775 5650)(-5475 5650);
WIRE 16 -1 (-5975 5200)(-5475 5200);
WIRE 16 -1 (-3875 1750)(-3450 1750);
WIRE 16 -1 (-3875 1800)(-3450 1800);
WIRE 16 -1 (-3875 1850)(-3450 1850);
WIRE 16 -1 (-3450 1900)(-3875 1900);
WIRE 16 -1 (-3875 1950)(-3450 1950);
WIRE 16 -1 (-3875 2000)(-3450 2000);
WIRE 16 -1 (-3875 1650)(-3450 1650);
WIRE 16 -1 (-3875 1700)(-3450 1700);
WIRE 16 -1 (-3875 2850)(-3450 2850);
WIRE 16 -1 (-3875 2900)(-3450 2900);
WIRE 16 -1 (-3875 3000)(-3450 3000);
WIRE 16 -1 (-3875 3050)(-3450 3050);
WIRE 16 -1 (-3875 2100)(-3450 2100);
WIRE 16 -1 (-3875 2150)(-3450 2150);
WIRE 16 -1 (-3875 2550)(-3450 2550);
WIRE 16 -1 (-3875 2200)(-3450 2200);
WIRE 16 -1 (-3875 2600)(-3450 2600);
WIRE 16 -1 (-3875 2250)(-3450 2250);
WIRE 16 -1 (-3875 2300)(-3450 2300);
WIRE 16 -1 (-3875 2350)(-3450 2350);
WIRE 16 -1 (-3875 2400)(-3450 2400);
WIRE 16 -1 (-3875 2450)(-3450 2450);
WIRE 16 -1 (-3875 2650)(-3450 2650);
WIRE 16 -1 (-3875 2700)(-3450 2700);
WIRE 16 -1 (-3875 2750)(-3450 2750);
WIRE 16 -1 (-3875 2800)(-3450 2800);
WIRE 16 -1 (-3875 3500)(-3450 3500);
WIRE 16 -1 (-3875 3550)(-3450 3550);
WIRE 16 -1 (-3875 3600)(-3450 3600);
WIRE 16 -1 (-3875 3750)(-3450 3750);
WIRE 16 -1 (-3875 3650)(-3450 3650);
WIRE 16 -1 (-3875 3800)(-3450 3800);
WIRE 16 -1 (-3875 3700)(-3450 3700);
WIRE 16 -1 (-3875 3100)(-3450 3100);
WIRE 16 -1 (-3875 3900)(-3450 3900);
WIRE 16 -1 (-3875 3150)(-3450 3150);
WIRE 16 -1 (-3875 3950)(-3450 3950);
WIRE 16 -1 (-3875 4000)(-3450 4000);
WIRE 16 -1 (-3875 4050)(-3450 4050);
WIRE 16 -1 (-3875 3200)(-3450 3200);
WIRE 16 -1 (-3875 3250)(-3450 3250);
WIRE 16 -1 (-3875 3300)(-3450 3300);
WIRE 16 -1 (-3875 3350)(-3450 3350);
WIRE 16 -1 (-3875 3450)(-3450 3450);
WIRE 16 -1 (-3875 5000)(-3450 5000);
WIRE 16 -1 (-3875 5050)(-3450 5050);
WIRE 16 -1 (-3875 4450)(-3450 4450);
WIRE 16 -1 (-3875 5100)(-3450 5100);
WIRE 16 -1 (-3875 4500)(-3450 4500);
WIRE 16 -1 (-3875 4550)(-3450 4550);
WIRE 16 -1 (-3875 4600)(-3450 4600);
WIRE 16 -1 (-3875 4650)(-3450 4650);
WIRE 16 -1 (-3875 4700)(-3450 4700);
WIRE 16 -1 (-3875 4800)(-3450 4800);
WIRE 16 -1 (-3875 4850)(-3450 4850);
WIRE 16 -1 (-3875 4100)(-3450 4100);
WIRE 16 -1 (-3875 4900)(-3450 4900);
WIRE 16 -1 (-3875 4150)(-3450 4150);
WIRE 16 -1 (-3875 4950)(-3450 4950);
WIRE 16 -1 (-3875 4350)(-3450 4350);
WIRE 16 -1 (-3875 4200)(-3450 4200);
WIRE 16 -1 (-3875 4400)(-3450 4400);
WIRE 16 -1 (-3875 4250)(-3450 4250);
WIRE 16 -1 (-3875 5550)(-3450 5550);
WIRE 16 -1 (-3875 5150)(-3450 5150);
WIRE 16 -1 (-3875 5600)(-3450 5600);
WIRE 16 -1 (-3875 5250)(-3450 5250);
WIRE 16 -1 (-3875 5700)(-3450 5700);
WIRE 16 -1 (-3875 5300)(-3450 5300);
WIRE 16 -1 (-3875 5750)(-3450 5750);
WIRE 16 -1 (-3875 5350)(-3450 5350);
WIRE 16 -1 (-3875 5800)(-3450 5800);
WIRE 16 -1 (-3875 5400)(-3450 5400);
WIRE 16 -1 (-3875 5850)(-3450 5850);
WIRE 16 -1 (-3875 5450)(-3450 5450);
WIRE 16 -1 (-3875 5900)(-3450 5900);
WIRE 16 -1 (-3875 5500)(-3450 5500);
WIRE 16 -1 (-3875 5950)(-3450 5950);
WIRE 16 -1 (-3875 6000)(-3450 6000);
WIRE 16 -1 (-3875 6050)(-3450 6050);
QUIT
